FILE_TYPE = MACRO_DRAWING;
SET COLOR_WIRE YELLOW;
SET COLOR_PROP ORANGE;
SET COLOR_DOT WHITE;
SET COLOR_ARC YELLOW;
SET COLOR_BODY GREEN;
SET COLOR_NOTE PURPLE;
SET PROP_DISPLAY VALUE;
SET PAGE_NUMBER P194;
FORCEADD UNIVERSAL_GND..1
(850 900);
FORCEPROP 3 LASTPIN (850 950) SIG_NAME GND\g
J 0
(860 960);
DISPLAY 0.659574 (860 960);
PAINT MONO (860 960);
DISPLAY INVISIBLE (860 960);
FORCEPROP 2 LAST CDS_LIB pure_quanta_power
J 0
(850 900);
DISPLAY INVISIBLE (850 900);
FORCEPROP 1 LAST HDL_POWER GND
J 1
(875 825);
DISPLAY 0.872340 (875 825);
PAINT GREEN (875 825);
DISPLAY INVISIBLE (875 825);
FORCEPROP 1 LAST PATH I1
J 0
(925 900);
DISPLAY 0.872340 (925 900);
PAINT AQUA (925 900);
DISPLAY INVISIBLE (925 900);
FORCEADD OFFPAGE..5
(1825 1475);
FORCEPROP 2 LAST $XR0 217 
J 0
(1570 1475);
DISPLAY 0.638298 (1570 1475);
PAINT MONO (1570 1475);
FORCEPROP 2 LAST CDS_LIB standard
J 0
(1825 1475);
DISPLAY INVISIBLE (1825 1475);
FORCEPROP 1 LAST OFFPAGE TRUE
J 0
(2150 1350);
DISPLAY 0.872340 (2150 1350);
PAINT GREEN (2150 1350);
DISPLAY INVISIBLE (2150 1350);
FORCEPROP 1 LAST COMMENT_BODY TRUE
J 0
(1925 1400);
DISPLAY 0.872340 (1925 1400);
PAINT GREEN (1925 1400);
DISPLAY INVISIBLE (1925 1400);
FORCEPROP 2 LAST PATH I10
J 0
(1575 1525);
DISPLAY 0.680851 (1575 1525);
DISPLAY INVISIBLE (1575 1525);
FORCEADD UNIVERSAL_GND..1
(875 3725);
FORCEPROP 3 LASTPIN (875 3775) SIG_NAME GND\g
J 0
(885 3785);
DISPLAY 0.659574 (885 3785);
PAINT MONO (885 3785);
DISPLAY INVISIBLE (885 3785);
FORCEPROP 2 LAST CDS_LIB pure_quanta_power
J 0
(875 3725);
DISPLAY INVISIBLE (875 3725);
FORCEPROP 1 LAST HDL_POWER GND
J 1
(900 3650);
DISPLAY 0.872340 (900 3650);
PAINT GREEN (900 3650);
DISPLAY INVISIBLE (900 3650);
FORCEPROP 1 LAST PATH I11
J 0
(950 3725);
DISPLAY 0.872340 (950 3725);
PAINT AQUA (950 3725);
DISPLAY INVISIBLE (950 3725);
FORCEADD Q_CAP..1
(875 3925);
FORCEPROP 1 LAST LOCATION PC404_3
J 0
(925 4025);
DISPLAY 0.489362 (925 4025);
PAINT SKYBLUE (925 4025);
FORCEPROP 0 LAST $SEC 1
J 0
(925 4050);
DISPLAY 0.680851 (925 4050);
PAINT MONO (925 4050);
DISPLAY INVISIBLE (925 4050);
FORCEPROP 0 LAST CDS_SEC 1
J 0
(1125 3975);
DISPLAY 1.021277 (1125 3975);
DISPLAY INVISIBLE (1125 3975);
FORCEPROP 1 LASTPIN (875 4025) $PN 1
J 0
(885 4005);
DISPLAY 0.489362 (885 4005);
PAINT MONO (885 4005);
FORCEPROP 1 LASTPIN (875 3825) $PN 2
J 0
(885 3805);
DISPLAY 0.489362 (885 3805);
PAINT MONO (885 3805);
FORCEPROP 1 LAST MATERIAL X7R
J 0
(925 3825);
DISPLAY 0.489362 (925 3825);
PAINT SKYBLUE (925 3825);
FORCEPROP 1 LAST TOLERANCE 10%
J 0
(925 3875);
DISPLAY 0.489362 (925 3875);
PAINT SKYBLUE (925 3875);
FORCEPROP 1 LAST VALUE 0.1UF
J 0
(925 3975);
DISPLAY 0.489362 (925 3975);
PAINT SKYBLUE (925 3975);
FORCEPROP 1 LAST VOLTAGE 25V
J 0
(925 3925);
DISPLAY 0.489362 (925 3925);
PAINT SKYBLUE (925 3925);
FORCEPROP 1 LAST PACK_TYPE 0402
J 0
(925 3725);
DISPLAY 0.489362 (925 3725);
PAINT SKYBLUE (925 3725);
FORCEPROP 2 LAST CDS_LIB pure_quanta
J 0
(875 3925);
DISPLAY INVISIBLE (875 3925);
FORCEPROP 1 LAST PATH I12
J 0
(925 4075);
DISPLAY 0.978723 (925 4075);
PAINT WHITE (925 4075);
DISPLAY INVISIBLE (925 4075);
FORCEPROP 1 LAST PART_NUMBER CH4104K1B00
J 0
(925 3775);
DISPLAY 0.489362 (925 3775);
PAINT SKYBLUE (925 3775);
DISPLAY INVISIBLE (925 3775);
FORCEADD Q_RES..2
(1500 2475);
FORCEPROP 1 LAST LOCATION PR264
J 0
(1545 2600);
DISPLAY 0.489362 (1545 2600);
PAINT SKYBLUE (1545 2600);
FORCEPROP 0 LAST $SEC 1
J 0
(1550 2650);
DISPLAY 0.680851 (1550 2650);
PAINT MONO (1550 2650);
DISPLAY INVISIBLE (1550 2650);
FORCEPROP 0 LAST CDS_SEC 1
J 0
(1550 2650);
DISPLAY 1.021277 (1550 2650);
DISPLAY INVISIBLE (1550 2650);
FORCEPROP 1 LASTPIN (1500 2575) $PN 1
J 0
(1505 2537);
DISPLAY 0.489362 (1505 2537);
PAINT MONO (1505 2537);
FORCEPROP 1 LASTPIN (1500 2375) $PN 2
J 0
(1505 2385);
DISPLAY 0.489362 (1505 2385);
PAINT MONO (1505 2385);
FORCEPROP 1 LAST PACK_TYPE 0402LF
J 0
(1550 2300);
DISPLAY 0.489362 (1550 2300);
PAINT SKYBLUE (1550 2300);
FORCEPROP 1 LAST VALUE 2.2
J 0
(1550 2550);
DISPLAY 0.489362 (1550 2550);
PAINT SKYBLUE (1550 2550);
FORCEPROP 1 LAST TOLERANCE 1%
J 0
(1550 2500);
DISPLAY 0.489362 (1550 2500);
PAINT SKYBLUE (1550 2500);
FORCEPROP 1 LAST MATERIAL CHIP
J 0
(1550 2400);
DISPLAY 0.489362 (1550 2400);
PAINT SKYBLUE (1550 2400);
FORCEPROP 1 LAST WATTAGE 1/16W
J 0
(1550 2450);
DISPLAY 0.489362 (1550 2450);
PAINT SKYBLUE (1550 2450);
FORCEPROP 2 LAST CDS_LIB pure_quanta
J 0
(1500 2475);
DISPLAY INVISIBLE (1500 2475);
FORCEPROP 1 LAST PATH I13
J 0
(1550 2650);
DISPLAY 0.978723 (1550 2650);
PAINT WHITE (1550 2650);
DISPLAY INVISIBLE (1550 2650);
FORCEPROP 1 LAST PART_NUMBER CS-2202FB01
J 0
(1550 2350);
DISPLAY 0.489362 (1550 2350);
PAINT SKYBLUE (1550 2350);
DISPLAY INVISIBLE (1550 2350);
FORCEADD VCC_CORE..1
(1500 2875);
FORCEPROP 3 LASTPIN (1500 2825) SIG_NAME PVDDCR_CPU1_P1_PVCC\g
J 0
(1510 2835);
DISPLAY 0.659574 (1510 2835);
PAINT MONO (1510 2835);
DISPLAY INVISIBLE (1510 2835);
FORCEPROP 1 LAST HDL_POWER PVDDCR_CPU1_P1_PVCC
J 1
(1500 2925);
DISPLAY 0.489362 (1500 2925);
PAINT GREEN (1500 2925);
FORCEPROP 2 LAST CDS_LIB pure_quanta_power
J 0
(1500 2875);
DISPLAY INVISIBLE (1500 2875);
FORCEPROP 1 LAST PATH I14
J 0
(1550 2900);
DISPLAY 0.872340 (1550 2900);
PAINT AQUA (1550 2900);
DISPLAY INVISIBLE (1550 2900);
FORCEADD UNIVERSAL_GND..1
(1850 2225);
FORCEPROP 3 LASTPIN (1850 2275) SIG_NAME GND\g
J 0
(1860 2285);
DISPLAY 0.659574 (1860 2285);
PAINT MONO (1860 2285);
DISPLAY INVISIBLE (1860 2285);
FORCEPROP 2 LAST CDS_LIB pure_quanta_power
J 0
(1850 2225);
DISPLAY INVISIBLE (1850 2225);
FORCEPROP 1 LAST HDL_POWER GND
J 1
(1875 2150);
DISPLAY 0.872340 (1875 2150);
PAINT GREEN (1875 2150);
DISPLAY INVISIBLE (1875 2150);
FORCEPROP 1 LAST PATH I15
J 0
(1925 2225);
DISPLAY 0.872340 (1925 2225);
PAINT AQUA (1925 2225);
DISPLAY INVISIBLE (1925 2225);
FORCEADD Q_CAP..1
(1850 2500);
FORCEPROP 1 LAST LOCATION PC401_C1P1_4
J 0
(1900 2600);
DISPLAY 0.489362 (1900 2600);
PAINT SKYBLUE (1900 2600);
FORCEPROP 0 LAST $SEC 1
J 0
(1900 2650);
DISPLAY 0.680851 (1900 2650);
PAINT MONO (1900 2650);
DISPLAY INVISIBLE (1900 2650);
FORCEPROP 0 LAST CDS_SEC 1
J 0
(1900 2650);
DISPLAY 1.021277 (1900 2650);
DISPLAY INVISIBLE (1900 2650);
FORCEPROP 1 LASTPIN (1850 2600) $PN 1
J 0
(1860 2580);
DISPLAY 0.489362 (1860 2580);
PAINT MONO (1860 2580);
FORCEPROP 1 LASTPIN (1850 2400) $PN 2
J 0
(1860 2380);
DISPLAY 0.489362 (1860 2380);
PAINT MONO (1860 2380);
FORCEPROP 1 LAST TOLERANCE 10%
J 0
(1900 2450);
DISPLAY 0.489362 (1900 2450);
PAINT SKYBLUE (1900 2450);
FORCEPROP 1 LAST VALUE 2.2UF
J 0
(1900 2550);
DISPLAY 0.489362 (1900 2550);
PAINT SKYBLUE (1900 2550);
FORCEPROP 1 LAST PACK_TYPE C0402
J 0
(1900 2300);
DISPLAY 0.489362 (1900 2300);
PAINT SKYBLUE (1900 2300);
FORCEPROP 1 LAST MATERIAL X6S
J 0
(1900 2400);
DISPLAY 0.489362 (1900 2400);
PAINT SKYBLUE (1900 2400);
FORCEPROP 1 LAST VOLTAGE 10V
J 0
(1900 2500);
DISPLAY 0.489362 (1900 2500);
PAINT SKYBLUE (1900 2500);
FORCEPROP 2 LAST CDS_LIB pure_quanta
J 0
(1850 2500);
DISPLAY INVISIBLE (1850 2500);
FORCEPROP 1 LAST PATH I16
J 0
(1900 2650);
DISPLAY 0.978723 (1900 2650);
PAINT WHITE (1900 2650);
DISPLAY INVISIBLE (1900 2650);
FORCEPROP 1 LAST PART_NUMBER CH5222KEB01
J 0
(1900 2350);
DISPLAY 0.489362 (1900 2350);
PAINT SKYBLUE (1900 2350);
DISPLAY INVISIBLE (1900 2350);
FORCEADD UNIVERSAL_GND..1
(1375 3575);
FORCEPROP 3 LASTPIN (1375 3625) SIG_NAME GND\g
J 0
(1385 3635);
DISPLAY 0.659574 (1385 3635);
PAINT MONO (1385 3635);
DISPLAY INVISIBLE (1385 3635);
FORCEPROP 2 LAST CDS_LIB pure_quanta_power
J 0
(1375 3575);
PAINT MONO (1375 3575);
DISPLAY INVISIBLE (1375 3575);
FORCEPROP 1 LAST HDL_POWER GND
J 1
(1400 3500);
DISPLAY 0.872340 (1400 3500);
PAINT GREEN (1400 3500);
DISPLAY INVISIBLE (1400 3500);
FORCEPROP 1 LAST PATH I17
J 0
(1450 3575);
DISPLAY 0.872340 (1450 3575);
PAINT AQUA (1450 3575);
DISPLAY INVISIBLE (1450 3575);
FORCEADD Q_RES..2
R 2
(1375 3800);
FORCEPROP 1 LAST LOCATION PR263
J 2
(1330 3925);
DISPLAY 0.489362 (1330 3925);
PAINT SKYBLUE (1330 3925);
FORCEPROP 0 LAST $SEC 1
J 0
(1350 3975);
DISPLAY 0.680851 (1350 3975);
PAINT MONO (1350 3975);
DISPLAY INVISIBLE (1350 3975);
FORCEPROP 0 LAST CDS_SEC 1
J 0
(1350 3975);
DISPLAY 1.021277 (1350 3975);
DISPLAY INVISIBLE (1350 3975);
FORCEPROP 1 LASTPIN (1375 3900) $PN 1
J 2
(1370 3862);
DISPLAY 0.489362 (1370 3862);
PAINT MONO (1370 3862);
FORCEPROP 1 LASTPIN (1375 3700) $PN 2
J 2
(1370 3710);
DISPLAY 0.489362 (1370 3710);
PAINT MONO (1370 3710);
FORCEPROP 1 LAST MATERIAL EMPTY
J 2
(1335 3725);
DISPLAY 0.489362 (1335 3725);
PAINT RED (1335 3725);
FORCEPROP 1 LAST TOLERANCE 1%
J 2
(1330 3825);
DISPLAY 0.489362 (1330 3825);
PAINT SKYBLUE (1330 3825);
FORCEPROP 1 LAST VALUE 8.87K
J 2
(1330 3875);
DISPLAY 0.489362 (1330 3875);
PAINT SKYBLUE (1330 3875);
FORCEPROP 1 LAST WATTAGE 1/16W
J 2
(1335 3775);
DISPLAY 0.489362 (1335 3775);
PAINT SKYBLUE (1335 3775);
FORCEPROP 1 LAST PACK_TYPE 0402LF
J 2
(1335 3625);
DISPLAY 0.489362 (1335 3625);
PAINT SKYBLUE (1335 3625);
FORCEPROP 2 LAST CDS_LIB pure_quanta
J 2
(1375 3800);
DISPLAY INVISIBLE (1375 3800);
FORCEPROP 1 LAST PATH I18
J 2
(1325 3975);
DISPLAY 0.978723 (1325 3975);
PAINT WHITE (1325 3975);
DISPLAY INVISIBLE (1325 3975);
FORCEPROP 1 LAST PART_NUMBER CS28872FB01
J 2
(1335 3675);
DISPLAY 0.489362 (1335 3675);
PAINT SKYBLUE (1335 3675);
DISPLAY INVISIBLE (1335 3675);
FORCEADD OFFPAGE..1
(1850 3700);
FORCEPROP 2 LAST $XR0 217 
J 0
(1424 3700);
DISPLAY 0.638298 (1424 3700);
PAINT MONO (1424 3700);
FORCEPROP 2 LAST CDS_LIB standard
J 0
(1850 3700);
DISPLAY INVISIBLE (1850 3700);
FORCEPROP 1 LAST OFFPAGE TRUE
J 0
(2175 3575);
DISPLAY 0.872340 (2175 3575);
PAINT GREEN (2175 3575);
DISPLAY INVISIBLE (2175 3575);
FORCEPROP 1 LAST COMMENT_BODY TRUE
J 0
(1975 3600);
DISPLAY 0.872340 (1975 3600);
PAINT GREEN (1975 3600);
DISPLAY INVISIBLE (1975 3600);
FORCEPROP 2 LAST PATH I19
J 0
(1425 3750);
DISPLAY 0.680851 (1425 3750);
DISPLAY INVISIBLE (1425 3750);
FORCEADD Q_CAP..1
(850 1100);
FORCEPROP 1 LAST LOCATION PC403_4
J 0
(900 1200);
DISPLAY 0.489362 (900 1200);
PAINT SKYBLUE (900 1200);
FORCEPROP 0 LAST $SEC 1
J 0
(900 1225);
DISPLAY 0.680851 (900 1225);
PAINT MONO (900 1225);
DISPLAY INVISIBLE (900 1225);
FORCEPROP 0 LAST CDS_SEC 1
J 0
(1100 1150);
DISPLAY 1.021277 (1100 1150);
DISPLAY INVISIBLE (1100 1150);
FORCEPROP 1 LASTPIN (850 1200) $PN 1
J 0
(860 1180);
DISPLAY 0.489362 (860 1180);
PAINT MONO (860 1180);
FORCEPROP 1 LASTPIN (850 1000) $PN 2
J 0
(860 980);
DISPLAY 0.489362 (860 980);
PAINT MONO (860 980);
FORCEPROP 1 LAST MATERIAL X7R
J 0
(900 1000);
DISPLAY 0.489362 (900 1000);
PAINT SKYBLUE (900 1000);
FORCEPROP 1 LAST TOLERANCE 10%
J 0
(900 1050);
DISPLAY 0.489362 (900 1050);
PAINT SKYBLUE (900 1050);
FORCEPROP 1 LAST VALUE 0.1UF
J 0
(900 1150);
DISPLAY 0.489362 (900 1150);
PAINT SKYBLUE (900 1150);
FORCEPROP 1 LAST VOLTAGE 25V
J 0
(900 1100);
DISPLAY 0.489362 (900 1100);
PAINT SKYBLUE (900 1100);
FORCEPROP 1 LAST PACK_TYPE 0402
J 0
(900 900);
DISPLAY 0.489362 (900 900);
PAINT SKYBLUE (900 900);
FORCEPROP 2 LAST CDS_LIB pure_quanta
J 0
(850 1100);
DISPLAY INVISIBLE (850 1100);
FORCEPROP 1 LAST PATH I2
J 0
(900 1250);
DISPLAY 0.978723 (900 1250);
PAINT WHITE (900 1250);
DISPLAY INVISIBLE (900 1250);
FORCEPROP 1 LAST PART_NUMBER CH4104K1B00
J 0
(900 950);
DISPLAY 0.489362 (900 950);
PAINT SKYBLUE (900 950);
DISPLAY INVISIBLE (900 950);
FORCEADD OFFPAGE..5
(1850 3800);
FORCEPROP 2 LAST $XR3 217 
J 0
(1565 3728);
DISPLAY 0.638298 (1565 3728);
PAINT MONO (1565 3728);
FORCEPROP 2 LAST $XR2 220 
J 0
(1565 3836);
DISPLAY 0.638298 (1565 3836);
PAINT MONO (1565 3836);
FORCEPROP 2 LAST $XR1 219 
J 0
(1565 3764);
DISPLAY 0.638298 (1565 3764);
PAINT MONO (1565 3764);
FORCEPROP 2 LAST $XR0 218 
J 0
(1565 3800);
DISPLAY 0.638298 (1565 3800);
PAINT MONO (1565 3800);
FORCEPROP 2 LAST CDS_LIB standard
J 0
(1850 3800);
DISPLAY INVISIBLE (1850 3800);
FORCEPROP 1 LAST OFFPAGE TRUE
J 0
(2175 3675);
DISPLAY 0.872340 (2175 3675);
PAINT GREEN (2175 3675);
DISPLAY INVISIBLE (2175 3675);
FORCEPROP 1 LAST COMMENT_BODY TRUE
J 0
(1950 3725);
DISPLAY 0.872340 (1950 3725);
PAINT GREEN (1950 3725);
DISPLAY INVISIBLE (1950 3725);
FORCEPROP 2 LAST PATH I20
J 0
(1600 3875);
DISPLAY 0.680851 (1600 3875);
DISPLAY INVISIBLE (1600 3875);
FORCEADD ISL99390FRZTR5935..1
(3275 1475);
FORCEPROP 1 LAST LOCATION PU36
J 0
(2975 2350);
DISPLAY 0.489362 (2975 2350);
PAINT SKYBLUE (2975 2350);
FORCEPROP 2 LAST $SEC 1
J 0
(2975 2400);
DISPLAY 0.680851 (2975 2400);
PAINT MONO (2975 2400);
DISPLAY INVISIBLE (2975 2400);
FORCEPROP 2 LAST CDS_SEC 1
J 0
(2975 2400);
DISPLAY 1.021277 (2975 2400);
DISPLAY INVISIBLE (2975 2400);
FORCEPROP 2 LASTPIN (3675 1025) $PN 2
J 0
(3685 1035);
DISPLAY 0.489362 (3685 1035);
PAINT MONO (3685 1035);
FORCEPROP 2 LASTPIN (3675 1825) $PN 33
J 0
(3685 1835);
DISPLAY 0.489362 (3685 1835);
PAINT MONO (3685 1835);
FORCEPROP 2 LASTPIN (2825 1225) $PN 31
J 2
(2815 1235);
DISPLAY 0.489362 (2815 1235);
PAINT MONO (2815 1235);
FORCEPROP 2 LASTPIN (2825 1625) $PN 35
J 2
(2815 1635);
DISPLAY 0.489362 (2815 1635);
PAINT MONO (2815 1635);
FORCEPROP 2 LASTPIN (3675 1175) $PN 6
J 0
(3685 1185);
DISPLAY 0.489362 (3685 1185);
PAINT MONO (3685 1185);
FORCEPROP 2 LASTPIN (3675 1125) $PN 41
J 0
(3685 1135);
DISPLAY 0.489362 (3685 1135);
PAINT MONO (3685 1135);
FORCEPROP 2 LASTPIN (2825 1475) $PN 38
J 2
(2815 1485);
DISPLAY 0.489362 (2815 1485);
PAINT MONO (2815 1485);
FORCEPROP 2 LASTPIN (2825 1175) $PN 37
J 2
(2815 1185);
DISPLAY 0.489362 (2815 1185);
PAINT MONO (2815 1185);
FORCEPROP 2 LASTPIN (3675 975) $PN 5
J 0
(3685 985);
DISPLAY 0.489362 (3685 985);
PAINT MONO (3685 985);
FORCEPROP 2 LASTPIN (3675 925) $PN 7_9-20_24
J 0
(3685 935);
DISPLAY 0.489362 (3685 935);
PAINT MONO (3685 935);
FORCEPROP 2 LASTPIN (3675 875) $PN 40
J 0
(3685 885);
DISPLAY 0.489362 (3685 885);
PAINT MONO (3685 885);
FORCEPROP 2 LASTPIN (3675 1575) $PN 32
J 0
(3685 1585);
DISPLAY 0.489362 (3685 1585);
PAINT MONO (3685 1585);
FORCEPROP 2 LASTPIN (2825 2125) $PN 4
J 2
(2815 2135);
DISPLAY 0.489362 (2815 2135);
PAINT MONO (2815 2135);
FORCEPROP 2 LASTPIN (2825 875) $PN 34
J 2
(2815 885);
DISPLAY 0.489362 (2815 885);
PAINT MONO (2815 885);
FORCEPROP 2 LASTPIN (2825 1375) $PN 39
J 2
(2815 1385);
DISPLAY 0.489362 (2815 1385);
PAINT MONO (2815 1385);
FORCEPROP 2 LASTPIN (3675 1475) $PN 10_19
J 0
(3685 1485);
DISPLAY 0.489362 (3685 1485);
PAINT MONO (3685 1485);
FORCEPROP 2 LASTPIN (2825 975) $PN 36
J 2
(2815 985);
DISPLAY 0.489362 (2815 985);
PAINT MONO (2815 985);
FORCEPROP 2 LASTPIN (2825 1825) $PN 3
J 2
(2815 1835);
DISPLAY 0.489362 (2815 1835);
PAINT MONO (2815 1835);
FORCEPROP 2 LASTPIN (3675 2125) $PN 25_29
J 0
(3685 2135);
DISPLAY 0.489362 (3685 2135);
PAINT MONO (3685 2135);
FORCEPROP 2 LASTPIN (3675 2075) $PN 30
J 0
(3685 2085);
DISPLAY 0.489362 (3685 2085);
PAINT MONO (3685 2085);
FORCEPROP 2 LASTPIN (3675 1225) $PN 1
J 0
(3685 1235);
DISPLAY 0.489362 (3685 1235);
PAINT MONO (3685 1235);
FORCEPROP 2 LAST PART_TYPE SMLF
J 0
(2975 2500);
DISPLAY 0.638298 (2975 2500);
FORCEPROP 1 LAST MATERIAL IC
J 0
(2975 2200);
DISPLAY 0.489362 (2975 2200);
PAINT SKYBLUE (2975 2200);
FORCEPROP 2 LAST VALUE ISL99390FRZ-TR5935
J 0
(2975 2450);
DISPLAY 0.489362 (2975 2450);
PAINT SKYBLUE (2975 2450);
FORCEPROP 2 LAST CDS_LIB pure_quanta
J 0
(3275 1475);
DISPLAY INVISIBLE (3275 1475);
FORCEPROP 1 LAST CDS_LMAN_SYM_OUTLINE -300,700,250,-650
J 0
(3275 1475);
DISPLAY 0.468085 (3275 1475);
PAINT GREEN (3275 1475);
DISPLAY INVISIBLE (3275 1475);
FORCEPROP 1 LAST NEEDS_NO_SIZE TRUE
J 0
(3275 1475);
DISPLAY 0.723404 (3275 1475);
PAINT GREEN (3275 1475);
DISPLAY INVISIBLE (3275 1475);
FORCEPROP 1 LAST PATH I21
J 0
(3275 1475);
DISPLAY 0.723404 (3275 1475);
PAINT GREEN (3275 1475);
DISPLAY INVISIBLE (3275 1475);
FORCEPROP 1 LAST PART_NUMBER AL099390004
J 0
(2975 2275);
DISPLAY 0.489362 (2975 2275);
PAINT SKYBLUE (2975 2275);
DISPLAY INVISIBLE (2975 2275);
FORCEADD UNIVERSAL_GND..1
(3925 750);
FORCEPROP 3 LASTPIN (3925 800) SIG_NAME GND\g
J 0
(3935 810);
DISPLAY 0.659574 (3935 810);
PAINT MONO (3935 810);
DISPLAY INVISIBLE (3935 810);
FORCEPROP 2 LAST CDS_LIB pure_quanta_power
J 0
(3925 750);
PAINT MONO (3925 750);
DISPLAY INVISIBLE (3925 750);
FORCEPROP 1 LAST HDL_POWER GND
J 1
(3950 675);
DISPLAY 0.872340 (3950 675);
PAINT GREEN (3950 675);
DISPLAY INVISIBLE (3950 675);
FORCEPROP 1 LAST PATH I22
J 0
(4000 750);
DISPLAY 0.872340 (4000 750);
PAINT AQUA (4000 750);
DISPLAY INVISIBLE (4000 750);
FORCEADD Q_CAP..1
(4075 2400);
FORCEPROP 1 LAST LOCATION PC405_4
J 0
(4125 2500);
DISPLAY 0.489362 (4125 2500);
PAINT SKYBLUE (4125 2500);
FORCEPROP 0 LAST $SEC 1
J 0
(4125 2550);
DISPLAY 0.680851 (4125 2550);
PAINT MONO (4125 2550);
DISPLAY INVISIBLE (4125 2550);
FORCEPROP 0 LAST CDS_SEC 1
J 0
(4125 2550);
DISPLAY 1.021277 (4125 2550);
DISPLAY INVISIBLE (4125 2550);
FORCEPROP 1 LASTPIN (4075 2500) $PN 1
J 0
(4085 2480);
DISPLAY 0.489362 (4085 2480);
PAINT MONO (4085 2480);
FORCEPROP 1 LASTPIN (4075 2300) $PN 2
J 0
(4085 2280);
DISPLAY 0.489362 (4085 2280);
PAINT MONO (4085 2280);
FORCEPROP 1 LAST MATERIAL X7R
J 0
(4125 2300);
DISPLAY 0.489362 (4125 2300);
PAINT SKYBLUE (4125 2300);
FORCEPROP 1 LAST TOLERANCE 10%
J 0
(4125 2350);
DISPLAY 0.489362 (4125 2350);
PAINT SKYBLUE (4125 2350);
FORCEPROP 1 LAST VOLTAGE 25V
J 0
(4125 2400);
DISPLAY 0.489362 (4125 2400);
PAINT SKYBLUE (4125 2400);
FORCEPROP 1 LAST VALUE 0.1UF
J 0
(4125 2450);
DISPLAY 0.489362 (4125 2450);
PAINT SKYBLUE (4125 2450);
FORCEPROP 1 LAST PACK_TYPE 0402
J 0
(4125 2200);
DISPLAY 0.489362 (4125 2200);
PAINT SKYBLUE (4125 2200);
FORCEPROP 2 LAST CDS_LIB pure_quanta
J 0
(4075 2400);
DISPLAY INVISIBLE (4075 2400);
FORCEPROP 1 LAST PATH I23
J 0
(4125 2550);
DISPLAY 0.978723 (4125 2550);
PAINT WHITE (4125 2550);
DISPLAY INVISIBLE (4125 2550);
FORCEPROP 1 LAST PART_NUMBER CH4104K1B00
J 0
(4125 2250);
DISPLAY 0.489362 (4125 2250);
PAINT SKYBLUE (4125 2250);
DISPLAY INVISIBLE (4125 2250);
FORCEADD UNIVERSAL_GND..1
(3950 3575);
FORCEPROP 3 LASTPIN (3950 3625) SIG_NAME GND\g
J 0
(3960 3635);
DISPLAY 0.659574 (3960 3635);
PAINT MONO (3960 3635);
DISPLAY INVISIBLE (3960 3635);
FORCEPROP 2 LAST CDS_LIB pure_quanta_power
J 0
(3950 3575);
PAINT MONO (3950 3575);
DISPLAY INVISIBLE (3950 3575);
FORCEPROP 1 LAST HDL_POWER GND
J 1
(3975 3500);
DISPLAY 0.872340 (3975 3500);
PAINT GREEN (3975 3500);
DISPLAY INVISIBLE (3975 3500);
FORCEPROP 1 LAST PATH I24
J 0
(4025 3575);
DISPLAY 0.872340 (4025 3575);
PAINT AQUA (4025 3575);
DISPLAY INVISIBLE (4025 3575);
FORCEADD OFFPAGE..1
(1850 4200);
FORCEPROP 2 LAST $XR5 223 
J 0
(998 4200);
DISPLAY 0.638298 (998 4200);
PAINT MONO (998 4200);
FORCEPROP 2 LAST $XR4 222 
J 0
(1118 4200);
DISPLAY 0.638298 (1118 4200);
PAINT MONO (1118 4200);
FORCEPROP 2 LAST $XR3 220 
J 0
(1238 4200);
DISPLAY 0.638298 (1238 4200);
PAINT MONO (1238 4200);
FORCEPROP 2 LAST $XR2 219 
J 0
(1358 4200);
DISPLAY 0.638298 (1358 4200);
PAINT MONO (1358 4200);
FORCEPROP 2 LAST $XR1 218 
J 0
(1478 4200);
DISPLAY 0.638298 (1478 4200);
PAINT MONO (1478 4200);
FORCEPROP 2 LAST $XR0 217 
J 0
(1598 4200);
DISPLAY 0.638298 (1598 4200);
PAINT MONO (1598 4200);
FORCEPROP 2 LAST CDS_LIB standard
J 0
(1850 4200);
DISPLAY INVISIBLE (1850 4200);
FORCEPROP 1 LAST OFFPAGE TRUE
J 0
(2175 4075);
DISPLAY 0.872340 (2175 4075);
PAINT GREEN (2175 4075);
DISPLAY INVISIBLE (2175 4075);
FORCEPROP 1 LAST COMMENT_BODY TRUE
J 0
(1975 4100);
DISPLAY 0.872340 (1975 4100);
PAINT GREEN (1975 4100);
DISPLAY INVISIBLE (1975 4100);
FORCEPROP 2 LAST PATH I25
J 0
(1575 4250);
DISPLAY 0.680851 (1575 4250);
DISPLAY INVISIBLE (1575 4250);
FORCEADD OFFPAGE..5
(1850 4300);
FORCEPROP 2 LAST $XR0 217 
J 0
(1565 4300);
DISPLAY 0.638298 (1565 4300);
PAINT MONO (1565 4300);
FORCEPROP 2 LAST CDS_LIB standard
J 0
(1850 4300);
DISPLAY INVISIBLE (1850 4300);
FORCEPROP 1 LAST OFFPAGE TRUE
J 0
(2175 4175);
DISPLAY 0.872340 (2175 4175);
PAINT GREEN (2175 4175);
DISPLAY INVISIBLE (2175 4175);
FORCEPROP 1 LAST COMMENT_BODY TRUE
J 0
(1950 4225);
DISPLAY 0.872340 (1950 4225);
PAINT GREEN (1950 4225);
DISPLAY INVISIBLE (1950 4225);
FORCEPROP 2 LAST PATH I26
J 0
(1600 4350);
DISPLAY 0.680851 (1600 4350);
DISPLAY INVISIBLE (1600 4350);
FORCEADD Q_CAP..1
(1675 4750);
FORCEPROP 1 LAST LOCATION PC400
J 0
(1725 4850);
DISPLAY 0.489362 (1725 4850);
PAINT SKYBLUE (1725 4850);
FORCEPROP 0 LAST $SEC 1
J 0
(1725 4900);
DISPLAY 0.680851 (1725 4900);
PAINT MONO (1725 4900);
DISPLAY INVISIBLE (1725 4900);
FORCEPROP 0 LAST CDS_SEC 1
J 0
(1725 4900);
DISPLAY 1.021277 (1725 4900);
DISPLAY INVISIBLE (1725 4900);
FORCEPROP 1 LASTPIN (1675 4850) $PN 1
J 0
(1685 4830);
DISPLAY 0.489362 (1685 4830);
PAINT MONO (1685 4830);
FORCEPROP 1 LASTPIN (1675 4650) $PN 2
J 0
(1685 4630);
DISPLAY 0.489362 (1685 4630);
PAINT MONO (1685 4630);
FORCEPROP 1 LAST MATERIAL X6S
J 0
(1725 4650);
DISPLAY 0.489362 (1725 4650);
PAINT SKYBLUE (1725 4650);
FORCEPROP 1 LAST TOLERANCE 10%
J 0
(1725 4700);
DISPLAY 0.489362 (1725 4700);
PAINT SKYBLUE (1725 4700);
FORCEPROP 1 LAST VALUE 2.2UF
J 0
(1725 4800);
DISPLAY 0.489362 (1725 4800);
PAINT SKYBLUE (1725 4800);
FORCEPROP 1 LAST VOLTAGE 10V
J 0
(1725 4750);
DISPLAY 0.489362 (1725 4750);
PAINT SKYBLUE (1725 4750);
FORCEPROP 1 LAST PACK_TYPE C0402
J 0
(1725 4550);
DISPLAY 0.489362 (1725 4550);
PAINT SKYBLUE (1725 4550);
FORCEPROP 2 LAST CDS_LIB pure_quanta
J 0
(1675 4750);
DISPLAY INVISIBLE (1675 4750);
FORCEPROP 1 LAST PATH I27
J 0
(1725 4900);
DISPLAY 0.978723 (1725 4900);
PAINT WHITE (1725 4900);
DISPLAY INVISIBLE (1725 4900);
FORCEPROP 1 LAST PART_NUMBER CH5222KEB01
J 0
(1725 4600);
DISPLAY 0.489362 (1725 4600);
PAINT SKYBLUE (1725 4600);
DISPLAY INVISIBLE (1725 4600);
FORCEADD UNIVERSAL_GND..1
(1675 4550);
FORCEPROP 3 LASTPIN (1675 4600) SIG_NAME GND\g
J 0
(1685 4610);
DISPLAY 0.659574 (1685 4610);
PAINT MONO (1685 4610);
DISPLAY INVISIBLE (1685 4610);
FORCEPROP 2 LAST CDS_LIB pure_quanta_power
J 0
(1675 4550);
DISPLAY INVISIBLE (1675 4550);
FORCEPROP 1 LAST HDL_POWER GND
J 1
(1700 4475);
DISPLAY 0.872340 (1700 4475);
PAINT GREEN (1700 4475);
DISPLAY INVISIBLE (1700 4475);
FORCEPROP 1 LAST PATH I28
J 0
(1750 4550);
DISPLAY 0.872340 (1750 4550);
PAINT AQUA (1750 4550);
DISPLAY INVISIBLE (1750 4550);
FORCEADD Q_RES..2
(1675 5300);
FORCEPROP 1 LAST LOCATION PR265
J 0
(1720 5425);
DISPLAY 0.489362 (1720 5425);
PAINT SKYBLUE (1720 5425);
FORCEPROP 0 LAST $SEC 1
J 0
(1725 5475);
DISPLAY 0.680851 (1725 5475);
PAINT MONO (1725 5475);
DISPLAY INVISIBLE (1725 5475);
FORCEPROP 0 LAST CDS_SEC 1
J 0
(1725 5475);
DISPLAY 1.021277 (1725 5475);
DISPLAY INVISIBLE (1725 5475);
FORCEPROP 1 LASTPIN (1675 5400) $PN 1
J 0
(1680 5362);
DISPLAY 0.489362 (1680 5362);
PAINT MONO (1680 5362);
FORCEPROP 1 LASTPIN (1675 5200) $PN 2
J 0
(1680 5210);
DISPLAY 0.489362 (1680 5210);
PAINT MONO (1680 5210);
FORCEPROP 1 LAST VALUE 2.2
J 0
(1725 5375);
DISPLAY 0.489362 (1725 5375);
PAINT SKYBLUE (1725 5375);
FORCEPROP 1 LAST TOLERANCE 1%
J 0
(1725 5325);
DISPLAY 0.489362 (1725 5325);
PAINT SKYBLUE (1725 5325);
FORCEPROP 1 LAST WATTAGE 1/16W
J 0
(1725 5275);
DISPLAY 0.489362 (1725 5275);
PAINT SKYBLUE (1725 5275);
FORCEPROP 1 LAST MATERIAL CHIP
J 0
(1725 5225);
DISPLAY 0.489362 (1725 5225);
PAINT SKYBLUE (1725 5225);
FORCEPROP 1 LAST PACK_TYPE 0402LF
J 0
(1725 5125);
DISPLAY 0.489362 (1725 5125);
PAINT SKYBLUE (1725 5125);
FORCEPROP 2 LAST CDS_LIB pure_quanta
J 0
(1675 5300);
DISPLAY INVISIBLE (1675 5300);
FORCEPROP 1 LAST PATH I29
J 0
(1725 5475);
DISPLAY 0.978723 (1725 5475);
PAINT WHITE (1725 5475);
DISPLAY INVISIBLE (1725 5475);
FORCEPROP 1 LAST PART_NUMBER CS-2202FB01
J 0
(1725 5175);
DISPLAY 0.489362 (1725 5175);
PAINT SKYBLUE (1725 5175);
DISPLAY INVISIBLE (1725 5175);
FORCEADD UNIVERSAL_GND..1
(1350 750);
FORCEPROP 3 LASTPIN (1350 800) SIG_NAME GND\g
J 0
(1360 810);
DISPLAY 0.659574 (1360 810);
PAINT MONO (1360 810);
DISPLAY INVISIBLE (1360 810);
FORCEPROP 2 LAST CDS_LIB pure_quanta_power
J 0
(1350 750);
PAINT MONO (1350 750);
DISPLAY INVISIBLE (1350 750);
FORCEPROP 1 LAST HDL_POWER GND
J 1
(1375 675);
DISPLAY 0.872340 (1375 675);
PAINT GREEN (1375 675);
DISPLAY INVISIBLE (1375 675);
FORCEPROP 1 LAST PATH I3
J 0
(1425 750);
DISPLAY 0.872340 (1425 750);
PAINT AQUA (1425 750);
DISPLAY INVISIBLE (1425 750);
FORCEADD UNIVERSAL_GND..1
(2025 5050);
FORCEPROP 3 LASTPIN (2025 5100) SIG_NAME GND\g
J 0
(2035 5110);
DISPLAY 0.659574 (2035 5110);
PAINT MONO (2035 5110);
DISPLAY INVISIBLE (2035 5110);
FORCEPROP 2 LAST CDS_LIB pure_quanta_power
J 0
(2025 5050);
DISPLAY INVISIBLE (2025 5050);
FORCEPROP 1 LAST HDL_POWER GND
J 1
(2050 4975);
DISPLAY 0.872340 (2050 4975);
PAINT GREEN (2050 4975);
DISPLAY INVISIBLE (2050 4975);
FORCEPROP 1 LAST PATH I30
J 0
(2100 5050);
DISPLAY 0.872340 (2100 5050);
PAINT AQUA (2100 5050);
DISPLAY INVISIBLE (2100 5050);
FORCEADD Q_CAP..1
(2025 5325);
FORCEPROP 1 LAST LOCATION PC402_C1P1_3
J 0
(2075 5425);
DISPLAY 0.489362 (2075 5425);
PAINT SKYBLUE (2075 5425);
FORCEPROP 0 LAST $SEC 1
J 0
(2075 5475);
DISPLAY 0.680851 (2075 5475);
PAINT MONO (2075 5475);
DISPLAY INVISIBLE (2075 5475);
FORCEPROP 0 LAST CDS_SEC 1
J 0
(2075 5475);
DISPLAY 1.021277 (2075 5475);
DISPLAY INVISIBLE (2075 5475);
FORCEPROP 1 LASTPIN (2025 5425) $PN 1
J 0
(2035 5405);
DISPLAY 0.489362 (2035 5405);
PAINT MONO (2035 5405);
FORCEPROP 1 LASTPIN (2025 5225) $PN 2
J 0
(2035 5205);
DISPLAY 0.489362 (2035 5205);
PAINT MONO (2035 5205);
FORCEPROP 1 LAST MATERIAL X6S
J 0
(2075 5225);
DISPLAY 0.489362 (2075 5225);
PAINT SKYBLUE (2075 5225);
FORCEPROP 1 LAST TOLERANCE 10%
J 0
(2075 5275);
DISPLAY 0.489362 (2075 5275);
PAINT SKYBLUE (2075 5275);
FORCEPROP 1 LAST VALUE 2.2UF
J 0
(2075 5375);
DISPLAY 0.489362 (2075 5375);
PAINT SKYBLUE (2075 5375);
FORCEPROP 1 LAST VOLTAGE 10V
J 0
(2075 5325);
DISPLAY 0.489362 (2075 5325);
PAINT SKYBLUE (2075 5325);
FORCEPROP 1 LAST PACK_TYPE C0402
J 0
(2075 5125);
DISPLAY 0.489362 (2075 5125);
PAINT SKYBLUE (2075 5125);
FORCEPROP 2 LAST CDS_LIB pure_quanta
J 0
(2025 5325);
DISPLAY INVISIBLE (2025 5325);
FORCEPROP 1 LAST PATH I31
J 0
(2075 5475);
DISPLAY 0.978723 (2075 5475);
PAINT WHITE (2075 5475);
DISPLAY INVISIBLE (2075 5475);
FORCEPROP 1 LAST PART_NUMBER CH5222KEB01
J 0
(2075 5175);
DISPLAY 0.489362 (2075 5175);
PAINT SKYBLUE (2075 5175);
DISPLAY INVISIBLE (2075 5175);
FORCEADD VCC_CORE..1
(1675 5700);
FORCEPROP 3 LASTPIN (1675 5650) SIG_NAME PVDDCR_CPU1_P1_PVCC\g
J 0
(1685 5660);
DISPLAY 0.659574 (1685 5660);
PAINT MONO (1685 5660);
DISPLAY INVISIBLE (1685 5660);
FORCEPROP 1 LAST HDL_POWER PVDDCR_CPU1_P1_PVCC
J 1
(1675 5750);
DISPLAY 0.489362 (1675 5750);
PAINT GREEN (1675 5750);
FORCEPROP 2 LAST CDS_LIB pure_quanta_power
J 0
(1675 5700);
DISPLAY INVISIBLE (1675 5700);
FORCEPROP 1 LAST PATH I32
J 0
(1725 5725);
DISPLAY 0.872340 (1725 5725);
PAINT AQUA (1725 5725);
DISPLAY INVISIBLE (1725 5725);
FORCEADD Q_CAP..1
(4125 5250);
FORCEPROP 1 LAST LOCATION PC408_3
J 0
(4175 5350);
DISPLAY 0.489362 (4175 5350);
PAINT SKYBLUE (4175 5350);
FORCEPROP 0 LAST $SEC 1
J 0
(4175 5400);
DISPLAY 0.680851 (4175 5400);
PAINT MONO (4175 5400);
DISPLAY INVISIBLE (4175 5400);
FORCEPROP 0 LAST CDS_SEC 1
J 0
(4175 5400);
DISPLAY 1.021277 (4175 5400);
DISPLAY INVISIBLE (4175 5400);
FORCEPROP 1 LASTPIN (4125 5350) $PN 1
J 0
(4135 5330);
DISPLAY 0.489362 (4135 5330);
PAINT MONO (4135 5330);
FORCEPROP 1 LASTPIN (4125 5150) $PN 2
J 0
(4135 5130);
DISPLAY 0.489362 (4135 5130);
PAINT MONO (4135 5130);
FORCEPROP 1 LAST PACK_TYPE 0402
J 0
(4175 5050);
DISPLAY 0.489362 (4175 5050);
PAINT SKYBLUE (4175 5050);
FORCEPROP 1 LAST MATERIAL X7R
J 0
(4175 5150);
DISPLAY 0.489362 (4175 5150);
PAINT SKYBLUE (4175 5150);
FORCEPROP 1 LAST VALUE 0.1UF
J 0
(4175 5300);
DISPLAY 0.489362 (4175 5300);
PAINT SKYBLUE (4175 5300);
FORCEPROP 1 LAST VOLTAGE 25V
J 0
(4175 5250);
DISPLAY 0.489362 (4175 5250);
PAINT SKYBLUE (4175 5250);
FORCEPROP 1 LAST TOLERANCE 10%
J 0
(4175 5200);
DISPLAY 0.489362 (4175 5200);
PAINT SKYBLUE (4175 5200);
FORCEPROP 2 LAST CDS_LIB pure_quanta
J 0
(4125 5250);
DISPLAY INVISIBLE (4125 5250);
FORCEPROP 1 LAST PATH I33
J 0
(4175 5400);
DISPLAY 0.978723 (4175 5400);
PAINT WHITE (4175 5400);
DISPLAY INVISIBLE (4175 5400);
FORCEPROP 1 LAST PART_NUMBER CH4104K1B00
J 0
(4175 5100);
DISPLAY 0.489362 (4175 5100);
PAINT SKYBLUE (4175 5100);
DISPLAY INVISIBLE (4175 5100);
FORCEADD UNIVERSAL_GND..1
(4675 550);
FORCEPROP 3 LASTPIN (4675 600) SIG_NAME GND\g
J 0
(4685 610);
DISPLAY 0.659574 (4685 610);
PAINT MONO (4685 610);
DISPLAY INVISIBLE (4685 610);
FORCEPROP 2 LAST CDS_LIB pure_quanta_power
J 0
(4675 550);
DISPLAY INVISIBLE (4675 550);
FORCEPROP 1 LAST HDL_POWER GND
J 1
(4700 475);
DISPLAY 0.872340 (4700 475);
PAINT GREEN (4700 475);
DISPLAY INVISIBLE (4700 475);
FORCEPROP 1 LAST PATH I34
J 0
(4750 550);
DISPLAY 0.872340 (4750 550);
PAINT AQUA (4750 550);
DISPLAY INVISIBLE (4750 550);
FORCEADD Q_RES..2
(4675 775);
FORCEPROP 1 LAST LOCATION PR515
J 0
(4720 900);
DISPLAY 0.489362 (4720 900);
PAINT SKYBLUE (4720 900);
FORCEPROP 0 LAST $SEC 1
J 0
(4725 950);
DISPLAY 0.680851 (4725 950);
PAINT MONO (4725 950);
DISPLAY INVISIBLE (4725 950);
FORCEPROP 0 LAST CDS_SEC 1
J 0
(4725 950);
DISPLAY 1.021277 (4725 950);
DISPLAY INVISIBLE (4725 950);
FORCEPROP 1 LASTPIN (4675 875) $PN 1
J 0
(4680 837);
DISPLAY 0.489362 (4680 837);
PAINT MONO (4680 837);
FORCEPROP 1 LASTPIN (4675 675) $PN 2
J 0
(4680 685);
DISPLAY 0.489362 (4680 685);
PAINT MONO (4680 685);
FORCEPROP 1 LAST WATTAGE 1/8W
J 0
(4715 750);
DISPLAY 0.489362 (4715 750);
PAINT SKYBLUE (4715 750);
FORCEPROP 1 LAST TOLERANCE 1%
J 0
(4720 800);
DISPLAY 0.489362 (4720 800);
PAINT SKYBLUE (4720 800);
FORCEPROP 1 LAST VALUE 1.5
J 0
(4720 850);
DISPLAY 0.489362 (4720 850);
PAINT SKYBLUE (4720 850);
FORCEPROP 1 LAST PACK_TYPE 0402LF
J 0
(4715 600);
DISPLAY 0.489362 (4715 600);
PAINT SKYBLUE (4715 600);
FORCEPROP 1 LAST MATERIAL EMPTY
J 0
(4715 700);
DISPLAY 0.489362 (4715 700);
PAINT RED (4715 700);
FORCEPROP 2 LAST CDS_LIB pure_quanta
J 0
(4675 775);
DISPLAY INVISIBLE (4675 775);
FORCEPROP 1 LAST PATH I35
J 0
(4725 950);
DISPLAY 0.978723 (4725 950);
PAINT WHITE (4725 950);
DISPLAY INVISIBLE (4725 950);
FORCEPROP 1 LAST PART_NUMBER CS-1504FB00
J 0
(4715 650);
DISPLAY 0.489362 (4715 650);
PAINT SKYBLUE (4715 650);
DISPLAY INVISIBLE (4715 650);
FORCEADD Q_RES..1
(4600 1825);
FORCEPROP 1 LAST LOCATION PR266
J 0
(4375 1900);
DISPLAY 0.489362 (4375 1900);
PAINT SKYBLUE (4375 1900);
FORCEPROP 0 LAST $SEC 1
J 0
(4875 1925);
DISPLAY 0.680851 (4875 1925);
PAINT MONO (4875 1925);
DISPLAY INVISIBLE (4875 1925);
FORCEPROP 0 LAST CDS_SEC 1
J 0
(4875 1925);
DISPLAY 1.021277 (4875 1925);
DISPLAY INVISIBLE (4875 1925);
FORCEPROP 1 LASTPIN (4500 1825) $PN 1
J 0
(4512 1837);
DISPLAY 0.787234 (4512 1837);
PAINT MONO (4512 1837);
DISPLAY INVISIBLE (4512 1837);
FORCEPROP 1 LASTPIN (4700 1825) $PN 2
J 0
(4662 1837);
DISPLAY 0.787234 (4662 1837);
PAINT MONO (4662 1837);
DISPLAY INVISIBLE (4662 1837);
FORCEPROP 1 LAST WATTAGE 1/16W
J 2
(4875 1900);
DISPLAY 0.489362 (4875 1900);
PAINT SKYBLUE (4875 1900);
FORCEPROP 1 LAST PACK_TYPE 0402LF
J 0
(5000 1750);
DISPLAY 0.489362 (5000 1750);
PAINT SKYBLUE (5000 1750);
FORCEPROP 1 LAST TOLERANCE 1%
J 0
(4600 1900);
DISPLAY 0.489362 (4600 1900);
PAINT SKYBLUE (4600 1900);
FORCEPROP 1 LAST MATERIAL CHIP
J 0
(4450 1750);
DISPLAY 0.489362 (4450 1750);
PAINT SKYBLUE (4450 1750);
FORCEPROP 1 LAST VALUE 5.6
J 2
(4550 1900);
DISPLAY 0.489362 (4550 1900);
PAINT SKYBLUE (4550 1900);
FORCEPROP 2 LAST CDS_LIB pure_quanta
J 0
(4600 1825);
DISPLAY INVISIBLE (4600 1825);
FORCEPROP 1 LAST PATH I36
J 0
(4550 1975);
DISPLAY 0.978723 (4550 1975);
PAINT WHITE (4550 1975);
DISPLAY INVISIBLE (4550 1975);
FORCEPROP 1 LAST PART_NUMBER CS-5602FB01
J 0
(4625 1750);
DISPLAY 0.489362 (4625 1750);
PAINT SKYBLUE (4625 1750);
DISPLAY INVISIBLE (4625 1750);
FORCEADD Q_CAP..1
(4675 1275);
FORCEPROP 1 LAST LOCATION PC205
J 0
(4725 1375);
DISPLAY 0.489362 (4725 1375);
PAINT SKYBLUE (4725 1375);
FORCEPROP 0 LAST $SEC 1
J 0
(4725 1425);
DISPLAY 0.680851 (4725 1425);
PAINT MONO (4725 1425);
DISPLAY INVISIBLE (4725 1425);
FORCEPROP 0 LAST CDS_SEC 1
J 0
(4725 1425);
DISPLAY 1.021277 (4725 1425);
DISPLAY INVISIBLE (4725 1425);
FORCEPROP 1 LASTPIN (4675 1375) $PN 1
J 0
(4685 1355);
DISPLAY 0.489362 (4685 1355);
PAINT MONO (4685 1355);
FORCEPROP 1 LASTPIN (4675 1175) $PN 2
J 0
(4685 1155);
DISPLAY 0.489362 (4685 1155);
PAINT MONO (4685 1155);
FORCEPROP 1 LAST MATERIAL EMPTY
J 0
(4725 1175);
DISPLAY 0.489362 (4725 1175);
PAINT RED (4725 1175);
FORCEPROP 1 LAST TOLERANCE 10%
J 0
(4725 1225);
DISPLAY 0.489362 (4725 1225);
PAINT SKYBLUE (4725 1225);
FORCEPROP 1 LAST VALUE 560PF
J 0
(4725 1325);
DISPLAY 0.489362 (4725 1325);
PAINT SKYBLUE (4725 1325);
FORCEPROP 1 LAST VOLTAGE 50V
J 0
(4725 1275);
DISPLAY 0.489362 (4725 1275);
PAINT SKYBLUE (4725 1275);
FORCEPROP 1 LAST PACK_TYPE C0402
J 0
(4725 1075);
DISPLAY 0.489362 (4725 1075);
PAINT SKYBLUE (4725 1075);
FORCEPROP 2 LAST CDS_LIB pure_quanta
J 0
(4675 1275);
DISPLAY INVISIBLE (4675 1275);
FORCEPROP 1 LAST PATH I37
J 0
(4725 1425);
DISPLAY 0.978723 (4725 1425);
PAINT WHITE (4725 1425);
DISPLAY INVISIBLE (4725 1425);
FORCEPROP 1 LAST PART_NUMBER CH1566K1B09
J 0
(4725 1125);
DISPLAY 0.489362 (4725 1125);
PAINT SKYBLUE (4725 1125);
DISPLAY INVISIBLE (4725 1125);
FORCEADD Q_RES..1
(5975 475);
FORCEPROP 1 LAST LOCATION PR268
J 0
(5925 500);
DISPLAY 0.489362 (5925 500);
PAINT SKYBLUE (5925 500);
FORCEPROP 0 LAST $SEC 1
J 0
(6225 625);
DISPLAY 0.680851 (6225 625);
PAINT MONO (6225 625);
DISPLAY INVISIBLE (6225 625);
FORCEPROP 0 LAST CDS_SEC 1
J 0
(6225 625);
DISPLAY 1.021277 (6225 625);
DISPLAY INVISIBLE (6225 625);
FORCEPROP 1 LASTPIN (5875 475) $PN 1
J 0
(5887 487);
DISPLAY 0.489362 (5887 487);
PAINT MONO (5887 487);
FORCEPROP 1 LASTPIN (6075 475) $PN 2
J 0
(6037 487);
DISPLAY 0.489362 (6037 487);
PAINT MONO (6037 487);
FORCEPROP 1 LAST PACK_TYPE 0402LF
J 0
(6075 425);
DISPLAY 0.489362 (6075 425);
PAINT SKYBLUE (6075 425);
FORCEPROP 1 LAST VALUE 0
J 2
(5775 500);
DISPLAY 0.489362 (5775 500);
PAINT SKYBLUE (5775 500);
FORCEPROP 1 LAST TOLERANCE 5%
J 0
(5800 500);
DISPLAY 0.489362 (5800 500);
PAINT SKYBLUE (5800 500);
FORCEPROP 1 LAST MATERIAL CHIP
J 0
(6100 500);
DISPLAY 0.489362 (6100 500);
PAINT SKYBLUE (6100 500);
FORCEPROP 1 LAST WATTAGE 1/16W
J 2
(6200 550);
DISPLAY 0.489362 (6200 550);
PAINT SKYBLUE (6200 550);
FORCEPROP 2 LAST CDS_LIB pure_quanta
J 0
(5975 475);
DISPLAY INVISIBLE (5975 475);
FORCEPROP 1 LAST PATH I38
J 0
(5925 625);
DISPLAY 0.978723 (5925 625);
PAINT WHITE (5925 625);
DISPLAY INVISIBLE (5925 625);
FORCEPROP 1 LAST PART_NUMBER CS00002JB13
J 0
(5675 425);
DISPLAY 0.489362 (5675 425);
PAINT SKYBLUE (5675 425);
DISPLAY INVISIBLE (5675 425);
FORCEADD OFFPAGE..6
(5675 1225);
FORCEPROP 2 LAST $XR0 219 
J 0
(5395 1225);
DISPLAY 0.638298 (5395 1225);
PAINT MONO (5395 1225);
FORCEPROP 2 LAST CDS_LIB standard
J 0
(5675 1225);
DISPLAY INVISIBLE (5675 1225);
FORCEPROP 1 LAST OFFPAGE TRUE
J 0
(6000 1100);
DISPLAY 0.872340 (6000 1100);
PAINT GREEN (6000 1100);
DISPLAY INVISIBLE (6000 1100);
FORCEPROP 1 LAST COMMENT_BODY TRUE
J 0
(5775 1150);
DISPLAY 0.872340 (5775 1150);
PAINT GREEN (5775 1150);
DISPLAY INVISIBLE (5775 1150);
FORCEPROP 2 LAST PATH I39
J 0
(5400 1275);
DISPLAY 0.680851 (5400 1275);
DISPLAY INVISIBLE (5400 1275);
FORCEADD Q_RES..2
R 2
(1350 975);
FORCEPROP 1 LAST LOCATION PR262
J 2
(1305 1100);
DISPLAY 0.489362 (1305 1100);
PAINT SKYBLUE (1305 1100);
FORCEPROP 0 LAST $SEC 1
J 0
(1325 1150);
DISPLAY 0.680851 (1325 1150);
PAINT MONO (1325 1150);
DISPLAY INVISIBLE (1325 1150);
FORCEPROP 0 LAST CDS_SEC 1
J 0
(1325 1150);
DISPLAY 1.021277 (1325 1150);
DISPLAY INVISIBLE (1325 1150);
FORCEPROP 1 LASTPIN (1350 1075) $PN 1
J 2
(1345 1037);
DISPLAY 0.489362 (1345 1037);
PAINT MONO (1345 1037);
FORCEPROP 1 LASTPIN (1350 875) $PN 2
J 2
(1345 885);
DISPLAY 0.489362 (1345 885);
PAINT MONO (1345 885);
FORCEPROP 1 LAST PACK_TYPE 0402LF
J 2
(1310 800);
DISPLAY 0.489362 (1310 800);
PAINT SKYBLUE (1310 800);
FORCEPROP 1 LAST VALUE 8.87K
J 2
(1305 1050);
DISPLAY 0.489362 (1305 1050);
PAINT SKYBLUE (1305 1050);
FORCEPROP 1 LAST TOLERANCE 1%
J 2
(1305 1000);
DISPLAY 0.489362 (1305 1000);
PAINT SKYBLUE (1305 1000);
FORCEPROP 1 LAST MATERIAL EMPTY
J 2
(1310 900);
DISPLAY 0.489362 (1310 900);
PAINT RED (1310 900);
FORCEPROP 1 LAST WATTAGE 1/16W
J 2
(1310 950);
DISPLAY 0.489362 (1310 950);
PAINT SKYBLUE (1310 950);
FORCEPROP 2 LAST CDS_LIB pure_quanta
J 2
(1350 975);
DISPLAY INVISIBLE (1350 975);
FORCEPROP 1 LAST PATH I4
J 2
(1300 1150);
DISPLAY 0.978723 (1300 1150);
PAINT WHITE (1300 1150);
DISPLAY INVISIBLE (1300 1150);
FORCEPROP 1 LAST PART_NUMBER CS28872FB01
J 2
(1310 850);
DISPLAY 0.489362 (1310 850);
PAINT SKYBLUE (1310 850);
DISPLAY INVISIBLE (1310 850);
FORCEADD Q_CAP..1
(5500 1700);
FORCEPROP 1 LAST LOCATION PC413
J 0
(5550 1800);
DISPLAY 0.489362 (5550 1800);
PAINT SKYBLUE (5550 1800);
FORCEPROP 0 LAST $SEC 1
J 0
(5550 1850);
DISPLAY 0.680851 (5550 1850);
PAINT MONO (5550 1850);
DISPLAY INVISIBLE (5550 1850);
FORCEPROP 0 LAST CDS_SEC 1
J 2
(5550 1825);
DISPLAY 1.021277 (5550 1825);
DISPLAY INVISIBLE (5550 1825);
FORCEPROP 1 LASTPIN (5500 1800) $PN 1
J 0
(5510 1780);
DISPLAY 0.489362 (5510 1780);
PAINT MONO (5510 1780);
FORCEPROP 1 LASTPIN (5500 1600) $PN 2
J 0
(5510 1580);
DISPLAY 0.489362 (5510 1580);
PAINT MONO (5510 1580);
FORCEPROP 1 LAST VALUE 0.22UF
J 0
(5550 1750);
DISPLAY 0.489362 (5550 1750);
PAINT SKYBLUE (5550 1750);
FORCEPROP 1 LAST MATERIAL X7R
J 0
(5550 1600);
DISPLAY 0.489362 (5550 1600);
PAINT SKYBLUE (5550 1600);
FORCEPROP 1 LAST TOLERANCE 10%
J 0
(5550 1650);
DISPLAY 0.489362 (5550 1650);
PAINT SKYBLUE (5550 1650);
FORCEPROP 1 LAST PACK_TYPE 0402
J 0
(5550 1500);
DISPLAY 0.489362 (5550 1500);
PAINT SKYBLUE (5550 1500);
FORCEPROP 1 LAST VOLTAGE 16V
J 0
(5550 1700);
DISPLAY 0.489362 (5550 1700);
PAINT SKYBLUE (5550 1700);
FORCEPROP 2 LAST CDS_LIB pure_quanta
J 2
(5500 1700);
DISPLAY INVISIBLE (5500 1700);
FORCEPROP 1 LAST PATH I40
J 0
(5550 1850);
DISPLAY 0.978723 (5550 1850);
PAINT WHITE (5550 1850);
DISPLAY INVISIBLE (5550 1850);
FORCEPROP 1 LAST PART_NUMBER CH4223K1B00
J 0
(5550 1550);
DISPLAY 0.489362 (5550 1550);
PAINT SKYBLUE (5550 1550);
DISPLAY INVISIBLE (5550 1550);
FORCEADD Q_CAP..1
(4475 2375);
FORCEPROP 1 LAST LOCATION PC407_4
J 0
(4525 2525);
DISPLAY 0.489362 (4525 2525);
PAINT SKYBLUE (4525 2525);
FORCEPROP 0 LAST $SEC 1
J 0
(4525 2575);
DISPLAY 0.680851 (4525 2575);
PAINT MONO (4525 2575);
DISPLAY INVISIBLE (4525 2575);
FORCEPROP 0 LAST CDS_SEC 1
J 0
(4525 2575);
DISPLAY 1.021277 (4525 2575);
DISPLAY INVISIBLE (4525 2575);
FORCEPROP 1 LASTPIN (4475 2475) $PN 1
J 0
(4485 2455);
DISPLAY 0.489362 (4485 2455);
PAINT MONO (4485 2455);
FORCEPROP 1 LASTPIN (4475 2275) $PN 2
J 0
(4485 2255);
DISPLAY 0.489362 (4485 2255);
PAINT MONO (4485 2255);
FORCEPROP 1 LAST TOLERANCE 10%
J 0
(4525 2375);
DISPLAY 0.489362 (4525 2375);
PAINT SKYBLUE (4525 2375);
FORCEPROP 1 LAST VALUE 1UF
J 0
(4525 2475);
DISPLAY 0.489362 (4525 2475);
PAINT SKYBLUE (4525 2475);
FORCEPROP 1 LAST VOLTAGE 25V
J 0
(4525 2425);
DISPLAY 0.489362 (4525 2425);
PAINT SKYBLUE (4525 2425);
FORCEPROP 1 LAST PACK_TYPE C0402
J 0
(4525 2275);
DISPLAY 0.489362 (4525 2275);
PAINT SKYBLUE (4525 2275);
FORCEPROP 1 LAST MATERIAL X6S
J 0
(4525 2325);
DISPLAY 0.489362 (4525 2325);
PAINT SKYBLUE (4525 2325);
FORCEPROP 2 LAST CDS_LIB pure_quanta
J 0
(4475 2375);
DISPLAY INVISIBLE (4475 2375);
FORCEPROP 1 LAST PATH I41
J 0
(4525 2525);
DISPLAY 0.978723 (4525 2525);
PAINT WHITE (4525 2525);
DISPLAY INVISIBLE (4525 2525);
FORCEPROP 1 LAST PART_NUMBER CH5104KEB02
J 0
(4525 2225);
DISPLAY 0.489362 (4525 2225);
PAINT SKYBLUE (4525 2225);
DISPLAY INVISIBLE (4525 2225);
FORCEADD Q_CAP..1
(4875 2375);
FORCEPROP 1 LAST LOCATION PC409_4
J 0
(4925 2525);
DISPLAY 0.489362 (4925 2525);
PAINT SKYBLUE (4925 2525);
FORCEPROP 0 LAST $SEC 1
J 0
(4925 2575);
DISPLAY 0.680851 (4925 2575);
PAINT MONO (4925 2575);
DISPLAY INVISIBLE (4925 2575);
FORCEPROP 0 LAST CDS_SEC 1
J 0
(4925 2575);
DISPLAY 1.021277 (4925 2575);
DISPLAY INVISIBLE (4925 2575);
FORCEPROP 1 LASTPIN (4875 2475) $PN 1
J 0
(4885 2455);
DISPLAY 0.489362 (4885 2455);
PAINT MONO (4885 2455);
FORCEPROP 1 LASTPIN (4875 2275) $PN 2
J 0
(4885 2255);
DISPLAY 0.489362 (4885 2255);
PAINT MONO (4885 2255);
FORCEPROP 1 LAST PACK_TYPE C0805
J 0
(4925 2275);
DISPLAY 0.489362 (4925 2275);
PAINT SKYBLUE (4925 2275);
FORCEPROP 1 LAST MATERIAL X6S
J 0
(4925 2325);
DISPLAY 0.489362 (4925 2325);
PAINT SKYBLUE (4925 2325);
FORCEPROP 1 LAST VALUE 22UF
J 0
(4925 2475);
DISPLAY 0.489362 (4925 2475);
PAINT SKYBLUE (4925 2475);
FORCEPROP 1 LAST VOLTAGE 16V
J 0
(4925 2425);
DISPLAY 0.489362 (4925 2425);
PAINT SKYBLUE (4925 2425);
FORCEPROP 1 LAST TOLERANCE 20%
J 0
(4925 2375);
DISPLAY 0.489362 (4925 2375);
PAINT SKYBLUE (4925 2375);
FORCEPROP 2 LAST CDS_LIB pure_quanta
J 0
(4875 2375);
DISPLAY INVISIBLE (4875 2375);
FORCEPROP 1 LAST PATH I42
J 0
(4925 2525);
DISPLAY 0.978723 (4925 2525);
PAINT WHITE (4925 2525);
DISPLAY INVISIBLE (4925 2525);
FORCEPROP 1 LAST PART_NUMBER CH6223MEA01
J 0
(4925 2225);
DISPLAY 0.489362 (4925 2225);
PAINT SKYBLUE (4925 2225);
DISPLAY INVISIBLE (4925 2225);
FORCEADD UNIVERSAL_GND..1
(4775 3325);
FORCEPROP 3 LASTPIN (4775 3375) SIG_NAME GND\g
J 0
(4785 3385);
DISPLAY 0.659574 (4785 3385);
PAINT MONO (4785 3385);
DISPLAY INVISIBLE (4785 3385);
FORCEPROP 2 LAST CDS_LIB pure_quanta_power
J 0
(4775 3325);
DISPLAY INVISIBLE (4775 3325);
FORCEPROP 1 LAST HDL_POWER GND
J 1
(4800 3250);
DISPLAY 0.872340 (4800 3250);
PAINT GREEN (4800 3250);
DISPLAY INVISIBLE (4800 3250);
FORCEPROP 1 LAST PATH I43
J 0
(4850 3325);
DISPLAY 0.872340 (4850 3325);
PAINT AQUA (4850 3325);
DISPLAY INVISIBLE (4850 3325);
FORCEADD Q_RES..2
(4775 3550);
FORCEPROP 1 LAST LOCATION PR516
J 0
(4820 3675);
DISPLAY 0.489362 (4820 3675);
PAINT SKYBLUE (4820 3675);
FORCEPROP 0 LAST $SEC 1
J 0
(4825 3725);
DISPLAY 0.680851 (4825 3725);
PAINT MONO (4825 3725);
DISPLAY INVISIBLE (4825 3725);
FORCEPROP 0 LAST CDS_SEC 1
J 0
(4825 3725);
DISPLAY 1.021277 (4825 3725);
DISPLAY INVISIBLE (4825 3725);
FORCEPROP 1 LASTPIN (4775 3650) $PN 1
J 0
(4780 3612);
DISPLAY 0.489362 (4780 3612);
PAINT MONO (4780 3612);
FORCEPROP 1 LASTPIN (4775 3450) $PN 2
J 0
(4780 3460);
DISPLAY 0.489362 (4780 3460);
PAINT MONO (4780 3460);
FORCEPROP 1 LAST WATTAGE 1/8W
J 0
(4815 3525);
DISPLAY 0.489362 (4815 3525);
PAINT SKYBLUE (4815 3525);
FORCEPROP 1 LAST TOLERANCE 1%
J 0
(4820 3575);
DISPLAY 0.489362 (4820 3575);
PAINT SKYBLUE (4820 3575);
FORCEPROP 1 LAST VALUE 1.5
J 0
(4820 3625);
DISPLAY 0.489362 (4820 3625);
PAINT SKYBLUE (4820 3625);
FORCEPROP 1 LAST MATERIAL EMPTY
J 0
(4815 3475);
DISPLAY 0.489362 (4815 3475);
PAINT RED (4815 3475);
FORCEPROP 1 LAST PACK_TYPE 0402LF
J 0
(4815 3375);
DISPLAY 0.489362 (4815 3375);
PAINT SKYBLUE (4815 3375);
FORCEPROP 2 LAST CDS_LIB pure_quanta
J 0
(4775 3550);
DISPLAY INVISIBLE (4775 3550);
FORCEPROP 1 LAST PATH I44
J 0
(4825 3725);
DISPLAY 0.978723 (4825 3725);
PAINT WHITE (4825 3725);
DISPLAY INVISIBLE (4825 3725);
FORCEPROP 1 LAST PART_NUMBER CS-1504FB00
J 0
(4815 3425);
DISPLAY 0.489362 (4815 3425);
PAINT SKYBLUE (4815 3425);
DISPLAY INVISIBLE (4815 3425);
FORCEADD Q_CAP..1
(5275 2375);
FORCEPROP 1 LAST LOCATION PC411_4
J 0
(5325 2525);
DISPLAY 0.489362 (5325 2525);
PAINT SKYBLUE (5325 2525);
FORCEPROP 0 LAST $SEC 1
J 0
(5325 2575);
DISPLAY 0.680851 (5325 2575);
PAINT MONO (5325 2575);
DISPLAY INVISIBLE (5325 2575);
FORCEPROP 0 LAST CDS_SEC 1
J 0
(5325 2575);
DISPLAY 1.021277 (5325 2575);
DISPLAY INVISIBLE (5325 2575);
FORCEPROP 1 LASTPIN (5275 2475) $PN 1
J 0
(5285 2455);
DISPLAY 0.489362 (5285 2455);
PAINT MONO (5285 2455);
FORCEPROP 1 LASTPIN (5275 2275) $PN 2
J 0
(5285 2255);
DISPLAY 0.489362 (5285 2255);
PAINT MONO (5285 2255);
FORCEPROP 1 LAST MATERIAL X6S
J 0
(5325 2325);
DISPLAY 0.489362 (5325 2325);
PAINT SKYBLUE (5325 2325);
FORCEPROP 1 LAST PACK_TYPE C0805
J 0
(5325 2275);
DISPLAY 0.489362 (5325 2275);
PAINT SKYBLUE (5325 2275);
FORCEPROP 1 LAST VALUE 22UF
J 0
(5325 2475);
DISPLAY 0.489362 (5325 2475);
PAINT SKYBLUE (5325 2475);
FORCEPROP 1 LAST VOLTAGE 16V
J 0
(5325 2425);
DISPLAY 0.489362 (5325 2425);
PAINT SKYBLUE (5325 2425);
FORCEPROP 1 LAST TOLERANCE 20%
J 0
(5325 2375);
DISPLAY 0.489362 (5325 2375);
PAINT SKYBLUE (5325 2375);
FORCEPROP 2 LAST CDS_LIB pure_quanta
J 0
(5275 2375);
DISPLAY INVISIBLE (5275 2375);
FORCEPROP 1 LAST PATH I45
J 0
(5325 2525);
DISPLAY 0.978723 (5325 2525);
PAINT WHITE (5325 2525);
DISPLAY INVISIBLE (5325 2525);
FORCEPROP 1 LAST PART_NUMBER CH6223MEA01
J 0
(5325 2225);
DISPLAY 0.489362 (5325 2225);
PAINT SKYBLUE (5325 2225);
DISPLAY INVISIBLE (5325 2225);
FORCEADD UNIVERSAL_GND..1
(5650 2000);
FORCEPROP 3 LASTPIN (5650 2050) SIG_NAME GND\g
J 0
(5660 2060);
DISPLAY 0.659574 (5660 2060);
PAINT MONO (5660 2060);
DISPLAY INVISIBLE (5660 2060);
FORCEPROP 2 LAST CDS_LIB pure_quanta_power
J 0
(5650 2000);
PAINT MONO (5650 2000);
DISPLAY INVISIBLE (5650 2000);
FORCEPROP 1 LAST HDL_POWER GND
J 1
(5675 1925);
DISPLAY 0.872340 (5675 1925);
PAINT GREEN (5675 1925);
DISPLAY INVISIBLE (5675 1925);
FORCEPROP 1 LAST PATH I46
J 0
(5725 2000);
DISPLAY 0.872340 (5725 2000);
PAINT AQUA (5725 2000);
DISPLAY INVISIBLE (5725 2000);
FORCEADD Q_CAP..1
(5650 2375);
FORCEPROP 1 LAST LOCATION PC415_4
J 0
(5700 2525);
DISPLAY 0.489362 (5700 2525);
PAINT SKYBLUE (5700 2525);
FORCEPROP 0 LAST $SEC 1
J 0
(5700 2575);
DISPLAY 0.680851 (5700 2575);
PAINT MONO (5700 2575);
DISPLAY INVISIBLE (5700 2575);
FORCEPROP 0 LAST CDS_SEC 1
J 0
(5700 2575);
DISPLAY 1.021277 (5700 2575);
DISPLAY INVISIBLE (5700 2575);
FORCEPROP 1 LASTPIN (5650 2475) $PN 1
J 0
(5660 2455);
DISPLAY 0.489362 (5660 2455);
PAINT MONO (5660 2455);
FORCEPROP 1 LASTPIN (5650 2275) $PN 2
J 0
(5660 2255);
DISPLAY 0.489362 (5660 2255);
PAINT MONO (5660 2255);
FORCEPROP 1 LAST PACK_TYPE C0805
J 0
(5700 2275);
DISPLAY 0.489362 (5700 2275);
PAINT SKYBLUE (5700 2275);
FORCEPROP 1 LAST MATERIAL X6S
J 0
(5700 2325);
DISPLAY 0.489362 (5700 2325);
PAINT SKYBLUE (5700 2325);
FORCEPROP 1 LAST VALUE 22UF
J 0
(5700 2475);
DISPLAY 0.489362 (5700 2475);
PAINT SKYBLUE (5700 2475);
FORCEPROP 1 LAST VOLTAGE 16V
J 0
(5700 2425);
DISPLAY 0.489362 (5700 2425);
PAINT SKYBLUE (5700 2425);
FORCEPROP 1 LAST TOLERANCE 20%
J 0
(5700 2375);
DISPLAY 0.489362 (5700 2375);
PAINT SKYBLUE (5700 2375);
FORCEPROP 2 LAST CDS_LIB pure_quanta
J 0
(5650 2375);
DISPLAY INVISIBLE (5650 2375);
FORCEPROP 1 LAST PATH I47
J 0
(5700 2525);
DISPLAY 0.978723 (5700 2525);
PAINT WHITE (5700 2525);
DISPLAY INVISIBLE (5700 2525);
FORCEPROP 1 LAST PART_NUMBER CH6223MEA01
J 0
(5700 2225);
DISPLAY 0.489362 (5700 2225);
PAINT SKYBLUE (5700 2225);
DISPLAY INVISIBLE (5700 2225);
FORCEADD VCC_CORE..1
(5650 2725);
FORCEPROP 3 LASTPIN (5650 2675) SIG_NAME SW_P12V_AUX_PVDDCR_CPU1_P1_FLT\g
J 0
(5660 2685);
DISPLAY 0.659574 (5660 2685);
PAINT MONO (5660 2685);
DISPLAY INVISIBLE (5660 2685);
FORCEPROP 1 LAST HDL_POWER SW_P12V_AUX_PVDDCR_CPU1_P1_FLT
J 1
(5650 2775);
DISPLAY 0.489362 (5650 2775);
PAINT GREEN (5650 2775);
FORCEPROP 2 LAST CDS_LIB pure_quanta_power
J 0
(5650 2725);
DISPLAY INVISIBLE (5650 2725);
FORCEPROP 1 LAST PATH I48
J 0
(5700 2750);
DISPLAY 0.872340 (5700 2750);
PAINT AQUA (5700 2750);
DISPLAY INVISIBLE (5700 2750);
FORCEADD Q_RES..1
(5900 3125);
FORCEPROP 1 LAST LOCATION PR269
J 0
(5850 3150);
DISPLAY 0.489362 (5850 3150);
PAINT SKYBLUE (5850 3150);
FORCEPROP 0 LAST $SEC 1
J 0
(6150 3275);
DISPLAY 0.680851 (6150 3275);
PAINT MONO (6150 3275);
DISPLAY INVISIBLE (6150 3275);
FORCEPROP 0 LAST CDS_SEC 1
J 0
(6150 3275);
DISPLAY 1.021277 (6150 3275);
DISPLAY INVISIBLE (6150 3275);
FORCEPROP 1 LASTPIN (5800 3125) $PN 1
J 0
(5812 3137);
DISPLAY 0.489362 (5812 3137);
PAINT MONO (5812 3137);
FORCEPROP 1 LASTPIN (6000 3125) $PN 2
J 0
(5962 3137);
DISPLAY 0.489362 (5962 3137);
PAINT MONO (5962 3137);
FORCEPROP 1 LAST PACK_TYPE 0402LF
J 0
(6000 3075);
DISPLAY 0.489362 (6000 3075);
PAINT SKYBLUE (6000 3075);
FORCEPROP 1 LAST MATERIAL CHIP
J 0
(6025 3150);
DISPLAY 0.489362 (6025 3150);
PAINT SKYBLUE (6025 3150);
FORCEPROP 1 LAST WATTAGE 1/16W
J 2
(6125 3200);
DISPLAY 0.489362 (6125 3200);
PAINT SKYBLUE (6125 3200);
FORCEPROP 1 LAST VALUE 0
J 2
(5700 3150);
DISPLAY 0.489362 (5700 3150);
PAINT SKYBLUE (5700 3150);
FORCEPROP 1 LAST TOLERANCE 5%
J 0
(5725 3150);
DISPLAY 0.489362 (5725 3150);
PAINT SKYBLUE (5725 3150);
FORCEPROP 2 LAST CDS_LIB pure_quanta
J 0
(5900 3125);
DISPLAY INVISIBLE (5900 3125);
FORCEPROP 1 LAST PATH I49
J 0
(5850 3275);
DISPLAY 0.978723 (5850 3275);
PAINT WHITE (5850 3275);
DISPLAY INVISIBLE (5850 3275);
FORCEPROP 1 LAST PART_NUMBER CS00002JB13
J 0
(5600 3075);
DISPLAY 0.489362 (5600 3075);
PAINT SKYBLUE (5600 3075);
DISPLAY INVISIBLE (5600 3075);
FORCEADD OFFPAGE..1
(1825 875);
FORCEPROP 2 LAST $XR0 217 
J 0
(1399 875);
DISPLAY 0.638298 (1399 875);
PAINT MONO (1399 875);
FORCEPROP 2 LAST CDS_LIB standard
J 0
(1825 875);
DISPLAY INVISIBLE (1825 875);
FORCEPROP 1 LAST OFFPAGE TRUE
J 0
(2150 750);
DISPLAY 0.872340 (2150 750);
PAINT GREEN (2150 750);
DISPLAY INVISIBLE (2150 750);
FORCEPROP 1 LAST COMMENT_BODY TRUE
J 0
(1950 775);
DISPLAY 0.872340 (1950 775);
PAINT GREEN (1950 775);
DISPLAY INVISIBLE (1950 775);
FORCEPROP 2 LAST PATH I5
J 0
(1550 925);
DISPLAY 0.680851 (1550 925);
DISPLAY INVISIBLE (1550 925);
FORCEADD Q_INDUCTOR4P_14..1
(6650 1350);
FORCEPROP 1 LAST LOCATION PL43
J 0
(6425 1605);
DISPLAY 0.489362 (6425 1605);
PAINT SKYBLUE (6425 1605);
FORCEPROP 0 LAST $SEC 1
J 0
(6425 1650);
DISPLAY 0.680851 (6425 1650);
PAINT MONO (6425 1650);
DISPLAY INVISIBLE (6425 1650);
FORCEPROP 0 LAST CDS_SEC 1
J 0
(6425 1650);
DISPLAY 1.021277 (6425 1650);
DISPLAY INVISIBLE (6425 1650);
FORCEPROP 0 LASTPIN (6250 1475) $PN 1
J 2
(6240 1485);
DISPLAY 0.489362 (6240 1485);
PAINT MONO (6240 1485);
FORCEPROP 0 LASTPIN (6250 1225) $PN 2
J 2
(6240 1235);
DISPLAY 0.489362 (6240 1235);
PAINT MONO (6240 1235);
FORCEPROP 0 LASTPIN (7050 1225) $PN 3
J 0
(7060 1235);
DISPLAY 0.489362 (7060 1235);
PAINT MONO (7060 1235);
FORCEPROP 0 LASTPIN (7050 1475) $PN 4
J 0
(7060 1485);
DISPLAY 0.489362 (7060 1485);
PAINT MONO (7060 1485);
FORCEPROP 2 LAST PART_TYPE SMLF
J 0
(6575 1100);
DISPLAY 1.021277 (6575 1100);
FORCEPROP 1 LAST MATERIAL IND
J 0
(6450 1525);
DISPLAY 0.489362 (6450 1525);
PAINT SKYBLUE (6450 1525);
FORCEPROP 2 LAST VALUE 150NH
J 0
(6550 1525);
DISPLAY 0.489362 (6550 1525);
PAINT SKYBLUE (6550 1525);
FORCEPROP 1 LAST NEEDS_NO_SIZE TRUE
J 0
(6650 1350);
DISPLAY 0.468085 (6650 1350);
PAINT GREEN (6650 1350);
DISPLAY INVISIBLE (6650 1350);
FORCEPROP 2 LAST CDS_LIB pure_quanta
J 0
(6650 1350);
DISPLAY INVISIBLE (6650 1350);
FORCEPROP 1 LAST PATH I50
J 0
(6850 1505);
DISPLAY 0.723404 (6850 1505);
PAINT GREEN (6850 1505);
DISPLAY INVISIBLE (6850 1505);
FORCEPROP 1 LAST PART_NUMBER CV+15^0TZ04
J 0
(6700 1525);
DISPLAY 0.489362 (6700 1525);
PAINT SKYBLUE (6700 1525);
DISPLAY INVISIBLE (6700 1525);
FORCEADD UNIVERSAL_GND..1
(7525 1125);
FORCEPROP 3 LASTPIN (7525 1175) SIG_NAME GND\g
J 0
(7535 1185);
DISPLAY 0.659574 (7535 1185);
PAINT MONO (7535 1185);
DISPLAY INVISIBLE (7535 1185);
FORCEPROP 2 LAST CDS_LIB pure_quanta_power
J 0
(7525 1125);
DISPLAY INVISIBLE (7525 1125);
FORCEPROP 1 LAST HDL_POWER GND
J 1
(7550 1050);
DISPLAY 0.872340 (7550 1050);
PAINT GREEN (7550 1050);
DISPLAY INVISIBLE (7550 1050);
FORCEPROP 1 LAST PATH I51
J 0
(7600 1125);
DISPLAY 0.872340 (7600 1125);
PAINT AQUA (7600 1125);
DISPLAY INVISIBLE (7600 1125);
FORCEADD Q_RES..1
(4675 4650);
FORCEPROP 1 LAST LOCATION PR267
J 0
(4450 4725);
DISPLAY 0.489362 (4450 4725);
PAINT SKYBLUE (4450 4725);
FORCEPROP 0 LAST $SEC 1
J 0
(4950 4750);
DISPLAY 0.680851 (4950 4750);
PAINT MONO (4950 4750);
DISPLAY INVISIBLE (4950 4750);
FORCEPROP 0 LAST CDS_SEC 1
J 0
(4950 4750);
DISPLAY 1.021277 (4950 4750);
DISPLAY INVISIBLE (4950 4750);
FORCEPROP 1 LASTPIN (4575 4650) $PN 1
J 0
(4587 4662);
DISPLAY 0.787234 (4587 4662);
PAINT MONO (4587 4662);
DISPLAY INVISIBLE (4587 4662);
FORCEPROP 1 LASTPIN (4775 4650) $PN 2
J 0
(4737 4662);
DISPLAY 0.787234 (4737 4662);
PAINT MONO (4737 4662);
DISPLAY INVISIBLE (4737 4662);
FORCEPROP 1 LAST WATTAGE 1/16W
J 2
(4950 4725);
DISPLAY 0.489362 (4950 4725);
PAINT SKYBLUE (4950 4725);
FORCEPROP 1 LAST TOLERANCE 1%
J 0
(4675 4725);
DISPLAY 0.489362 (4675 4725);
PAINT SKYBLUE (4675 4725);
FORCEPROP 1 LAST PACK_TYPE 0402LF
J 0
(5075 4575);
DISPLAY 0.489362 (5075 4575);
PAINT SKYBLUE (5075 4575);
FORCEPROP 1 LAST VALUE 5.6
J 2
(4625 4725);
DISPLAY 0.489362 (4625 4725);
PAINT SKYBLUE (4625 4725);
FORCEPROP 1 LAST MATERIAL CHIP
J 0
(4525 4575);
DISPLAY 0.489362 (4525 4575);
PAINT SKYBLUE (4525 4575);
FORCEPROP 2 LAST CDS_LIB pure_quanta
J 0
(4675 4650);
DISPLAY INVISIBLE (4675 4650);
FORCEPROP 1 LAST PATH I52
J 0
(4625 4800);
DISPLAY 0.978723 (4625 4800);
PAINT WHITE (4625 4800);
DISPLAY INVISIBLE (4625 4800);
FORCEPROP 1 LAST PART_NUMBER CS-5602FB01
J 0
(4700 4575);
DISPLAY 0.489362 (4700 4575);
PAINT SKYBLUE (4700 4575);
DISPLAY INVISIBLE (4700 4575);
FORCEADD Q_CAP..1
(4775 4100);
FORCEPROP 1 LAST LOCATION PC206
J 0
(4825 4200);
DISPLAY 0.489362 (4825 4200);
PAINT SKYBLUE (4825 4200);
FORCEPROP 0 LAST $SEC 1
J 0
(4825 4250);
DISPLAY 0.680851 (4825 4250);
PAINT MONO (4825 4250);
DISPLAY INVISIBLE (4825 4250);
FORCEPROP 0 LAST CDS_SEC 1
J 0
(4825 4250);
DISPLAY 1.021277 (4825 4250);
DISPLAY INVISIBLE (4825 4250);
FORCEPROP 1 LASTPIN (4775 4200) $PN 1
J 0
(4785 4180);
DISPLAY 0.489362 (4785 4180);
PAINT MONO (4785 4180);
FORCEPROP 1 LASTPIN (4775 4000) $PN 2
J 0
(4785 3980);
DISPLAY 0.489362 (4785 3980);
PAINT MONO (4785 3980);
FORCEPROP 1 LAST VALUE 560PF
J 0
(4825 4150);
DISPLAY 0.489362 (4825 4150);
PAINT SKYBLUE (4825 4150);
FORCEPROP 1 LAST VOLTAGE 50V
J 0
(4825 4100);
DISPLAY 0.489362 (4825 4100);
PAINT SKYBLUE (4825 4100);
FORCEPROP 1 LAST TOLERANCE 10%
J 0
(4825 4050);
DISPLAY 0.489362 (4825 4050);
PAINT SKYBLUE (4825 4050);
FORCEPROP 1 LAST MATERIAL EMPTY
J 0
(4825 4000);
DISPLAY 0.489362 (4825 4000);
PAINT RED (4825 4000);
FORCEPROP 1 LAST PACK_TYPE C0402
J 0
(4825 3900);
DISPLAY 0.489362 (4825 3900);
PAINT SKYBLUE (4825 3900);
FORCEPROP 2 LAST CDS_LIB pure_quanta
J 0
(4775 4100);
DISPLAY INVISIBLE (4775 4100);
FORCEPROP 1 LAST PATH I53
J 0
(4825 4250);
DISPLAY 0.978723 (4825 4250);
PAINT WHITE (4825 4250);
DISPLAY INVISIBLE (4825 4250);
FORCEPROP 1 LAST PART_NUMBER CH1566K1B09
J 0
(4825 3950);
DISPLAY 0.489362 (4825 3950);
PAINT SKYBLUE (4825 3950);
DISPLAY INVISIBLE (4825 3950);
FORCEADD Q_CAP..1
(4525 5225);
FORCEPROP 1 LAST LOCATION PC406_3
J 0
(4575 5375);
DISPLAY 0.489362 (4575 5375);
PAINT SKYBLUE (4575 5375);
FORCEPROP 0 LAST $SEC 1
J 0
(4575 5425);
DISPLAY 0.680851 (4575 5425);
PAINT MONO (4575 5425);
DISPLAY INVISIBLE (4575 5425);
FORCEPROP 0 LAST CDS_SEC 1
J 0
(4575 5425);
DISPLAY 1.021277 (4575 5425);
DISPLAY INVISIBLE (4575 5425);
FORCEPROP 1 LASTPIN (4525 5325) $PN 1
J 0
(4535 5305);
DISPLAY 0.489362 (4535 5305);
PAINT MONO (4535 5305);
FORCEPROP 1 LASTPIN (4525 5125) $PN 2
J 0
(4535 5105);
DISPLAY 0.489362 (4535 5105);
PAINT MONO (4535 5105);
FORCEPROP 1 LAST PACK_TYPE C0402
J 0
(4575 5125);
DISPLAY 0.489362 (4575 5125);
PAINT SKYBLUE (4575 5125);
FORCEPROP 1 LAST MATERIAL X6S
J 0
(4575 5175);
DISPLAY 0.489362 (4575 5175);
PAINT SKYBLUE (4575 5175);
FORCEPROP 1 LAST TOLERANCE 10%
J 0
(4575 5225);
DISPLAY 0.489362 (4575 5225);
PAINT SKYBLUE (4575 5225);
FORCEPROP 1 LAST VALUE 1UF
J 0
(4575 5325);
DISPLAY 0.489362 (4575 5325);
PAINT SKYBLUE (4575 5325);
FORCEPROP 1 LAST VOLTAGE 25V
J 0
(4575 5275);
DISPLAY 0.489362 (4575 5275);
PAINT SKYBLUE (4575 5275);
FORCEPROP 2 LAST CDS_LIB pure_quanta
J 0
(4525 5225);
DISPLAY INVISIBLE (4525 5225);
FORCEPROP 1 LAST PATH I54
J 0
(4575 5375);
DISPLAY 0.978723 (4575 5375);
PAINT WHITE (4575 5375);
DISPLAY INVISIBLE (4575 5375);
FORCEPROP 1 LAST PART_NUMBER CH5104KEB02
J 0
(4575 5075);
DISPLAY 0.489362 (4575 5075);
PAINT SKYBLUE (4575 5075);
DISPLAY INVISIBLE (4575 5075);
FORCEADD Q_CAP..1
(4925 5225);
FORCEPROP 1 LAST LOCATION PC410_3
J 0
(4975 5375);
DISPLAY 0.489362 (4975 5375);
PAINT SKYBLUE (4975 5375);
FORCEPROP 0 LAST $SEC 1
J 0
(4975 5425);
DISPLAY 0.680851 (4975 5425);
PAINT MONO (4975 5425);
DISPLAY INVISIBLE (4975 5425);
FORCEPROP 0 LAST CDS_SEC 1
J 0
(4975 5425);
DISPLAY 1.021277 (4975 5425);
DISPLAY INVISIBLE (4975 5425);
FORCEPROP 1 LASTPIN (4925 5325) $PN 1
J 0
(4935 5305);
DISPLAY 0.489362 (4935 5305);
PAINT MONO (4935 5305);
FORCEPROP 1 LASTPIN (4925 5125) $PN 2
J 0
(4935 5105);
DISPLAY 0.489362 (4935 5105);
PAINT MONO (4935 5105);
FORCEPROP 1 LAST TOLERANCE 20%
J 0
(4975 5225);
DISPLAY 0.489362 (4975 5225);
PAINT SKYBLUE (4975 5225);
FORCEPROP 1 LAST MATERIAL X6S
J 0
(4975 5175);
DISPLAY 0.489362 (4975 5175);
PAINT SKYBLUE (4975 5175);
FORCEPROP 1 LAST VOLTAGE 16V
J 0
(4975 5275);
DISPLAY 0.489362 (4975 5275);
PAINT SKYBLUE (4975 5275);
FORCEPROP 1 LAST VALUE 22UF
J 0
(4975 5325);
DISPLAY 0.489362 (4975 5325);
PAINT SKYBLUE (4975 5325);
FORCEPROP 1 LAST PACK_TYPE C0805
J 0
(4975 5125);
DISPLAY 0.489362 (4975 5125);
PAINT SKYBLUE (4975 5125);
FORCEPROP 2 LAST CDS_LIB pure_quanta
J 0
(4925 5225);
DISPLAY INVISIBLE (4925 5225);
FORCEPROP 1 LAST PATH I55
J 0
(4975 5375);
DISPLAY 0.978723 (4975 5375);
PAINT WHITE (4975 5375);
DISPLAY INVISIBLE (4975 5375);
FORCEPROP 1 LAST PART_NUMBER CH6223MEA01
J 0
(4975 5075);
DISPLAY 0.489362 (4975 5075);
PAINT SKYBLUE (4975 5075);
DISPLAY INVISIBLE (4975 5075);
FORCEADD OFFPAGE..6
(5600 4050);
FORCEPROP 2 LAST $XR0 218 
J 0
(5290 4050);
DISPLAY 0.638298 (5290 4050);
PAINT MONO (5290 4050);
FORCEPROP 2 LAST CDS_LIB standard
J 0
(5600 4050);
DISPLAY INVISIBLE (5600 4050);
FORCEPROP 1 LAST OFFPAGE TRUE
J 0
(5925 3925);
DISPLAY 0.872340 (5925 3925);
PAINT GREEN (5925 3925);
DISPLAY INVISIBLE (5925 3925);
FORCEPROP 1 LAST COMMENT_BODY TRUE
J 0
(5700 3975);
DISPLAY 0.872340 (5700 3975);
PAINT GREEN (5700 3975);
DISPLAY INVISIBLE (5700 3975);
FORCEPROP 2 LAST PATH I56
J 0
(5325 4100);
DISPLAY 0.680851 (5325 4100);
DISPLAY INVISIBLE (5325 4100);
FORCEADD Q_CAP..1
(5650 4525);
FORCEPROP 1 LAST LOCATION PC414
J 0
(5700 4625);
DISPLAY 0.489362 (5700 4625);
PAINT SKYBLUE (5700 4625);
FORCEPROP 0 LAST $SEC 1
J 0
(5700 4675);
DISPLAY 0.680851 (5700 4675);
PAINT MONO (5700 4675);
DISPLAY INVISIBLE (5700 4675);
FORCEPROP 0 LAST CDS_SEC 1
J 2
(5700 4650);
DISPLAY 1.021277 (5700 4650);
DISPLAY INVISIBLE (5700 4650);
FORCEPROP 1 LASTPIN (5650 4625) $PN 1
J 0
(5660 4605);
DISPLAY 0.489362 (5660 4605);
PAINT MONO (5660 4605);
FORCEPROP 1 LASTPIN (5650 4425) $PN 2
J 0
(5660 4405);
DISPLAY 0.489362 (5660 4405);
PAINT MONO (5660 4405);
FORCEPROP 1 LAST VOLTAGE 16V
J 0
(5700 4525);
DISPLAY 0.489362 (5700 4525);
PAINT SKYBLUE (5700 4525);
FORCEPROP 1 LAST MATERIAL X7R
J 0
(5700 4425);
DISPLAY 0.489362 (5700 4425);
PAINT SKYBLUE (5700 4425);
FORCEPROP 1 LAST VALUE 0.22UF
J 0
(5700 4575);
DISPLAY 0.489362 (5700 4575);
PAINT SKYBLUE (5700 4575);
FORCEPROP 1 LAST TOLERANCE 10%
J 0
(5700 4475);
DISPLAY 0.489362 (5700 4475);
PAINT SKYBLUE (5700 4475);
FORCEPROP 1 LAST PACK_TYPE 0402
J 0
(5700 4325);
DISPLAY 0.489362 (5700 4325);
PAINT SKYBLUE (5700 4325);
FORCEPROP 2 LAST CDS_LIB pure_quanta
J 2
(5650 4525);
DISPLAY INVISIBLE (5650 4525);
FORCEPROP 1 LAST PATH I57
J 0
(5700 4675);
DISPLAY 0.978723 (5700 4675);
PAINT WHITE (5700 4675);
DISPLAY INVISIBLE (5700 4675);
FORCEPROP 1 LAST PART_NUMBER CH4223K1B00
J 0
(5700 4375);
DISPLAY 0.489362 (5700 4375);
PAINT SKYBLUE (5700 4375);
DISPLAY INVISIBLE (5700 4375);
FORCEADD UNIVERSAL_GND..1
(5700 4875);
FORCEPROP 3 LASTPIN (5700 4925) SIG_NAME GND\g
J 0
(5710 4935);
DISPLAY 0.659574 (5710 4935);
PAINT MONO (5710 4935);
DISPLAY INVISIBLE (5710 4935);
FORCEPROP 2 LAST CDS_LIB pure_quanta_power
J 0
(5700 4875);
PAINT MONO (5700 4875);
DISPLAY INVISIBLE (5700 4875);
FORCEPROP 1 LAST HDL_POWER GND
J 1
(5725 4800);
DISPLAY 0.872340 (5725 4800);
PAINT GREEN (5725 4800);
DISPLAY INVISIBLE (5725 4800);
FORCEPROP 1 LAST PATH I58
J 0
(5775 4875);
DISPLAY 0.872340 (5775 4875);
PAINT AQUA (5775 4875);
DISPLAY INVISIBLE (5775 4875);
FORCEADD Q_CAP..1
(5325 5225);
FORCEPROP 1 LAST LOCATION PC412_3
J 0
(5375 5375);
DISPLAY 0.489362 (5375 5375);
PAINT SKYBLUE (5375 5375);
FORCEPROP 0 LAST $SEC 1
J 0
(5375 5425);
DISPLAY 0.680851 (5375 5425);
PAINT MONO (5375 5425);
DISPLAY INVISIBLE (5375 5425);
FORCEPROP 0 LAST CDS_SEC 1
J 0
(5375 5425);
DISPLAY 1.021277 (5375 5425);
DISPLAY INVISIBLE (5375 5425);
FORCEPROP 1 LASTPIN (5325 5325) $PN 1
J 0
(5335 5305);
DISPLAY 0.489362 (5335 5305);
PAINT MONO (5335 5305);
FORCEPROP 1 LASTPIN (5325 5125) $PN 2
J 0
(5335 5105);
DISPLAY 0.489362 (5335 5105);
PAINT MONO (5335 5105);
FORCEPROP 1 LAST VOLTAGE 16V
J 0
(5375 5275);
DISPLAY 0.489362 (5375 5275);
PAINT SKYBLUE (5375 5275);
FORCEPROP 1 LAST TOLERANCE 20%
J 0
(5375 5225);
DISPLAY 0.489362 (5375 5225);
PAINT SKYBLUE (5375 5225);
FORCEPROP 1 LAST PACK_TYPE C0805
J 0
(5375 5125);
DISPLAY 0.489362 (5375 5125);
PAINT SKYBLUE (5375 5125);
FORCEPROP 1 LAST MATERIAL X6S
J 0
(5375 5175);
DISPLAY 0.489362 (5375 5175);
PAINT SKYBLUE (5375 5175);
FORCEPROP 1 LAST VALUE 22UF
J 0
(5375 5325);
DISPLAY 0.489362 (5375 5325);
PAINT SKYBLUE (5375 5325);
FORCEPROP 2 LAST CDS_LIB pure_quanta
J 0
(5325 5225);
DISPLAY INVISIBLE (5325 5225);
FORCEPROP 1 LAST PATH I59
J 0
(5375 5375);
DISPLAY 0.978723 (5375 5375);
PAINT WHITE (5375 5375);
DISPLAY INVISIBLE (5375 5375);
FORCEPROP 1 LAST PART_NUMBER CH6223MEA01
J 0
(5375 5075);
DISPLAY 0.489362 (5375 5075);
PAINT SKYBLUE (5375 5075);
DISPLAY INVISIBLE (5375 5075);
FORCEADD UNIVERSAL_GND..1
(1500 1725);
FORCEPROP 3 LASTPIN (1500 1775) SIG_NAME GND\g
J 0
(1510 1785);
DISPLAY 0.659574 (1510 1785);
PAINT MONO (1510 1785);
DISPLAY INVISIBLE (1510 1785);
FORCEPROP 2 LAST CDS_LIB pure_quanta_power
J 0
(1500 1725);
DISPLAY INVISIBLE (1500 1725);
FORCEPROP 1 LAST HDL_POWER GND
J 1
(1525 1650);
DISPLAY 0.872340 (1525 1650);
PAINT GREEN (1525 1650);
DISPLAY INVISIBLE (1525 1650);
FORCEPROP 1 LAST PATH I6
J 0
(1575 1725);
DISPLAY 0.872340 (1575 1725);
PAINT AQUA (1575 1725);
DISPLAY INVISIBLE (1575 1725);
FORCEADD Q_CAP..1
(5700 5225);
FORCEPROP 1 LAST LOCATION PC416_3
J 0
(5750 5375);
DISPLAY 0.489362 (5750 5375);
PAINT SKYBLUE (5750 5375);
FORCEPROP 0 LAST $SEC 1
J 0
(5750 5425);
DISPLAY 0.680851 (5750 5425);
PAINT MONO (5750 5425);
DISPLAY INVISIBLE (5750 5425);
FORCEPROP 0 LAST CDS_SEC 1
J 0
(5750 5425);
DISPLAY 1.021277 (5750 5425);
DISPLAY INVISIBLE (5750 5425);
FORCEPROP 1 LASTPIN (5700 5325) $PN 1
J 0
(5710 5305);
DISPLAY 0.489362 (5710 5305);
PAINT MONO (5710 5305);
FORCEPROP 1 LASTPIN (5700 5125) $PN 2
J 0
(5710 5105);
DISPLAY 0.489362 (5710 5105);
PAINT MONO (5710 5105);
FORCEPROP 1 LAST MATERIAL X6S
J 0
(5750 5175);
DISPLAY 0.489362 (5750 5175);
PAINT SKYBLUE (5750 5175);
FORCEPROP 1 LAST TOLERANCE 20%
J 0
(5750 5225);
DISPLAY 0.489362 (5750 5225);
PAINT SKYBLUE (5750 5225);
FORCEPROP 1 LAST VOLTAGE 16V
J 0
(5750 5275);
DISPLAY 0.489362 (5750 5275);
PAINT SKYBLUE (5750 5275);
FORCEPROP 1 LAST PACK_TYPE C0805
J 0
(5750 5125);
DISPLAY 0.489362 (5750 5125);
PAINT SKYBLUE (5750 5125);
FORCEPROP 1 LAST VALUE 22UF
J 0
(5750 5325);
DISPLAY 0.489362 (5750 5325);
PAINT SKYBLUE (5750 5325);
FORCEPROP 2 LAST CDS_LIB pure_quanta
J 0
(5700 5225);
DISPLAY INVISIBLE (5700 5225);
FORCEPROP 1 LAST PATH I60
J 0
(5750 5375);
DISPLAY 0.978723 (5750 5375);
PAINT WHITE (5750 5375);
DISPLAY INVISIBLE (5750 5375);
FORCEPROP 1 LAST PART_NUMBER CH6223MEA01
J 0
(5750 5075);
DISPLAY 0.489362 (5750 5075);
PAINT SKYBLUE (5750 5075);
DISPLAY INVISIBLE (5750 5075);
FORCEADD VCC_CORE..1
(5700 5575);
FORCEPROP 3 LASTPIN (5700 5525) SIG_NAME SW_P12V_AUX_PVDDCR_CPU1_P1_FLT\g
J 0
(5710 5535);
DISPLAY 0.659574 (5710 5535);
PAINT MONO (5710 5535);
DISPLAY INVISIBLE (5710 5535);
FORCEPROP 1 LAST HDL_POWER SW_P12V_AUX_PVDDCR_CPU1_P1_FLT
J 1
(5700 5625);
DISPLAY 0.489362 (5700 5625);
PAINT GREEN (5700 5625);
FORCEPROP 2 LAST CDS_LIB pure_quanta_power
J 0
(5700 5575);
DISPLAY INVISIBLE (5700 5575);
FORCEPROP 1 LAST PATH I61
J 0
(5750 5600);
DISPLAY 0.872340 (5750 5600);
PAINT AQUA (5750 5600);
DISPLAY INVISIBLE (5750 5600);
FORCEADD Q_INDUCTOR4P_14..1
(6700 4175);
FORCEPROP 1 LAST LOCATION PL44
J 0
(6475 4430);
DISPLAY 0.489362 (6475 4430);
PAINT SKYBLUE (6475 4430);
FORCEPROP 0 LAST $SEC 1
J 0
(6475 4475);
DISPLAY 0.680851 (6475 4475);
PAINT MONO (6475 4475);
DISPLAY INVISIBLE (6475 4475);
FORCEPROP 0 LAST CDS_SEC 1
J 0
(6475 4475);
DISPLAY 1.021277 (6475 4475);
DISPLAY INVISIBLE (6475 4475);
FORCEPROP 0 LASTPIN (6300 4300) $PN 1
J 2
(6290 4310);
DISPLAY 0.489362 (6290 4310);
PAINT MONO (6290 4310);
FORCEPROP 0 LASTPIN (6300 4050) $PN 2
J 2
(6290 4060);
DISPLAY 0.489362 (6290 4060);
PAINT MONO (6290 4060);
FORCEPROP 0 LASTPIN (7100 4050) $PN 3
J 0
(7110 4060);
DISPLAY 0.489362 (7110 4060);
PAINT MONO (7110 4060);
FORCEPROP 0 LASTPIN (7100 4300) $PN 4
J 0
(7110 4310);
DISPLAY 0.489362 (7110 4310);
PAINT MONO (7110 4310);
FORCEPROP 2 LAST PART_TYPE SMLF
J 0
(6625 3925);
DISPLAY 1.021277 (6625 3925);
FORCEPROP 2 LAST VALUE 150NH
J 0
(6600 4350);
DISPLAY 0.489362 (6600 4350);
PAINT SKYBLUE (6600 4350);
FORCEPROP 1 LAST MATERIAL IND
J 0
(6500 4350);
DISPLAY 0.489362 (6500 4350);
PAINT SKYBLUE (6500 4350);
FORCEPROP 1 LAST NEEDS_NO_SIZE TRUE
J 0
(6700 4175);
DISPLAY 0.468085 (6700 4175);
PAINT GREEN (6700 4175);
DISPLAY INVISIBLE (6700 4175);
FORCEPROP 2 LAST CDS_LIB pure_quanta
J 0
(6700 4175);
DISPLAY INVISIBLE (6700 4175);
FORCEPROP 1 LAST PATH I62
J 0
(6900 4330);
DISPLAY 0.723404 (6900 4330);
PAINT GREEN (6900 4330);
DISPLAY INVISIBLE (6900 4330);
FORCEPROP 1 LAST PART_NUMBER CV+15^0TZ04
J 0
(6750 4350);
DISPLAY 0.489362 (6750 4350);
PAINT SKYBLUE (6750 4350);
DISPLAY INVISIBLE (6750 4350);
FORCEADD OFFPAGE..3
(7675 4050);
FORCEPROP 2 LAST $XR0 219 
J 0
(7889 4050);
DISPLAY 0.638298 (7889 4050);
PAINT MONO (7889 4050);
FORCEPROP 2 LAST CDS_LIB standard
J 0
(7675 4050);
DISPLAY INVISIBLE (7675 4050);
FORCEPROP 1 LAST OFFPAGE TRUE
J 0
(8000 3925);
DISPLAY 0.872340 (8000 3925);
PAINT GREEN (8000 3925);
DISPLAY INVISIBLE (8000 3925);
FORCEPROP 1 LAST COMMENT_BODY TRUE
J 0
(7625 3950);
DISPLAY 0.872340 (7625 3950);
PAINT GREEN (7625 3950);
DISPLAY INVISIBLE (7625 3950);
FORCEPROP 2 LAST PATH I63
J 0
(7900 4100);
DISPLAY 0.680851 (7900 4100);
DISPLAY INVISIBLE (7900 4100);
FORCEADD Q_CAP..1
(8175 4100);
FORCEPROP 1 LAST LOCATION PC417_3
J 0
(8225 4225);
DISPLAY 0.489362 (8225 4225);
PAINT SKYBLUE (8225 4225);
FORCEPROP 0 LAST $SEC 1
J 0
(8225 4275);
DISPLAY 0.680851 (8225 4275);
PAINT MONO (8225 4275);
DISPLAY INVISIBLE (8225 4275);
FORCEPROP 0 LAST CDS_SEC 1
J 0
(8225 4275);
DISPLAY 1.021277 (8225 4275);
DISPLAY INVISIBLE (8225 4275);
FORCEPROP 1 LASTPIN (8175 4200) $PN 1
J 0
(8185 4180);
DISPLAY 0.489362 (8185 4180);
PAINT MONO (8185 4180);
FORCEPROP 1 LASTPIN (8175 4000) $PN 2
J 0
(8185 3980);
DISPLAY 0.489362 (8185 3980);
PAINT MONO (8185 3980);
FORCEPROP 1 LAST VOLTAGE 4V
J 0
(8225 4125);
DISPLAY 0.489362 (8225 4125);
PAINT SKYBLUE (8225 4125);
FORCEPROP 1 LAST VALUE 22UF
J 0
(8225 4175);
DISPLAY 0.489362 (8225 4175);
PAINT SKYBLUE (8225 4175);
FORCEPROP 1 LAST TOLERANCE 20%
J 0
(8225 4075);
DISPLAY 0.489362 (8225 4075);
PAINT SKYBLUE (8225 4075);
FORCEPROP 1 LAST MATERIAL X6S
J 0
(8225 4025);
DISPLAY 0.489362 (8225 4025);
PAINT SKYBLUE (8225 4025);
FORCEPROP 1 LAST PACK_TYPE C0805
J 0
(8225 3975);
DISPLAY 0.489362 (8225 3975);
PAINT SKYBLUE (8225 3975);
FORCEPROP 2 LAST CDS_LIB pure_quanta
J 0
(8175 4100);
DISPLAY INVISIBLE (8175 4100);
FORCEPROP 1 LAST PATH I64
J 0
(8225 4250);
DISPLAY 0.978723 (8225 4250);
PAINT WHITE (8225 4250);
DISPLAY INVISIBLE (8225 4250);
FORCEPROP 1 LAST PART_NUMBER CH622KMEA03
J 0
(8225 3925);
DISPLAY 0.489362 (8225 3925);
PAINT SKYBLUE (8225 3925);
DISPLAY INVISIBLE (8225 3925);
FORCEADD Q_CAP..1
(8325 1275);
FORCEPROP 1 LAST LOCATION PC418_4
J 0
(8375 1400);
DISPLAY 0.489362 (8375 1400);
PAINT SKYBLUE (8375 1400);
FORCEPROP 0 LAST $SEC 1
J 0
(8375 1450);
DISPLAY 0.680851 (8375 1450);
PAINT MONO (8375 1450);
DISPLAY INVISIBLE (8375 1450);
FORCEPROP 0 LAST CDS_SEC 1
J 0
(8375 1450);
DISPLAY 1.021277 (8375 1450);
DISPLAY INVISIBLE (8375 1450);
FORCEPROP 1 LASTPIN (8325 1375) $PN 1
J 0
(8335 1355);
DISPLAY 0.489362 (8335 1355);
PAINT MONO (8335 1355);
FORCEPROP 1 LASTPIN (8325 1175) $PN 2
J 0
(8335 1155);
DISPLAY 0.489362 (8335 1155);
PAINT MONO (8335 1155);
FORCEPROP 1 LAST VOLTAGE 4V
J 0
(8375 1300);
DISPLAY 0.489362 (8375 1300);
PAINT SKYBLUE (8375 1300);
FORCEPROP 1 LAST VALUE 22UF
J 0
(8375 1350);
DISPLAY 0.489362 (8375 1350);
PAINT SKYBLUE (8375 1350);
FORCEPROP 1 LAST TOLERANCE 20%
J 0
(8375 1250);
DISPLAY 0.489362 (8375 1250);
PAINT SKYBLUE (8375 1250);
FORCEPROP 1 LAST MATERIAL X6S
J 0
(8375 1200);
DISPLAY 0.489362 (8375 1200);
PAINT SKYBLUE (8375 1200);
FORCEPROP 1 LAST PACK_TYPE C0805
J 0
(8375 1150);
DISPLAY 0.489362 (8375 1150);
PAINT SKYBLUE (8375 1150);
FORCEPROP 2 LAST CDS_LIB pure_quanta
J 0
(8325 1275);
DISPLAY INVISIBLE (8325 1275);
FORCEPROP 1 LAST PATH I65
J 0
(8375 1425);
DISPLAY 0.978723 (8375 1425);
PAINT WHITE (8375 1425);
DISPLAY INVISIBLE (8375 1425);
FORCEPROP 1 LAST PART_NUMBER CH622KMEA03
J 0
(8375 1100);
DISPLAY 0.489362 (8375 1100);
PAINT SKYBLUE (8375 1100);
DISPLAY INVISIBLE (8375 1100);
FORCEADD UNIVERSAL_GND..1
(8750 950);
FORCEPROP 3 LASTPIN (8750 1000) SIG_NAME GND\g
J 0
(8760 1010);
DISPLAY 0.659574 (8760 1010);
PAINT MONO (8760 1010);
DISPLAY INVISIBLE (8760 1010);
FORCEPROP 2 LAST CDS_LIB pure_quanta_power
J 0
(8750 950);
PAINT MONO (8750 950);
DISPLAY INVISIBLE (8750 950);
FORCEPROP 1 LAST HDL_POWER GND
J 1
(8775 875);
DISPLAY 0.872340 (8775 875);
PAINT GREEN (8775 875);
DISPLAY INVISIBLE (8775 875);
FORCEPROP 1 LAST PATH I66
J 0
(8825 950);
DISPLAY 0.872340 (8825 950);
PAINT AQUA (8825 950);
DISPLAY INVISIBLE (8825 950);
FORCEADD Q_CAP..1
(8750 1275);
FORCEPROP 1 LAST LOCATION PC420_4
J 0
(8800 1400);
DISPLAY 0.489362 (8800 1400);
PAINT SKYBLUE (8800 1400);
FORCEPROP 0 LAST $SEC 1
J 0
(8800 1450);
DISPLAY 0.680851 (8800 1450);
PAINT MONO (8800 1450);
DISPLAY INVISIBLE (8800 1450);
FORCEPROP 0 LAST CDS_SEC 1
J 0
(8800 1450);
DISPLAY 1.021277 (8800 1450);
DISPLAY INVISIBLE (8800 1450);
FORCEPROP 1 LASTPIN (8750 1375) $PN 1
J 0
(8760 1355);
DISPLAY 0.489362 (8760 1355);
PAINT MONO (8760 1355);
FORCEPROP 1 LASTPIN (8750 1175) $PN 2
J 0
(8760 1155);
DISPLAY 0.489362 (8760 1155);
PAINT MONO (8760 1155);
FORCEPROP 1 LAST VOLTAGE 4V
J 0
(8800 1300);
DISPLAY 0.489362 (8800 1300);
PAINT SKYBLUE (8800 1300);
FORCEPROP 1 LAST VALUE 22UF
J 0
(8800 1350);
DISPLAY 0.489362 (8800 1350);
PAINT SKYBLUE (8800 1350);
FORCEPROP 1 LAST TOLERANCE 20%
J 0
(8800 1250);
DISPLAY 0.489362 (8800 1250);
PAINT SKYBLUE (8800 1250);
FORCEPROP 1 LAST MATERIAL X6S
J 0
(8800 1200);
DISPLAY 0.489362 (8800 1200);
PAINT SKYBLUE (8800 1200);
FORCEPROP 1 LAST PACK_TYPE C0805
J 0
(8800 1150);
DISPLAY 0.489362 (8800 1150);
PAINT SKYBLUE (8800 1150);
FORCEPROP 2 LAST CDS_LIB pure_quanta
J 0
(8750 1275);
DISPLAY INVISIBLE (8750 1275);
FORCEPROP 1 LAST PATH I67
J 0
(8800 1425);
DISPLAY 0.978723 (8800 1425);
PAINT WHITE (8800 1425);
DISPLAY INVISIBLE (8800 1425);
FORCEPROP 1 LAST PART_NUMBER CH622KMEA03
J 0
(8800 1100);
DISPLAY 0.489362 (8800 1100);
PAINT SKYBLUE (8800 1100);
DISPLAY INVISIBLE (8800 1100);
FORCEADD VCC_CORE..1
(8750 1575);
FORCEPROP 3 LASTPIN (8750 1525) SIG_NAME PVDDCR_CPU1_P1\g
J 0
(8760 1535);
DISPLAY 0.659574 (8760 1535);
PAINT MONO (8760 1535);
DISPLAY INVISIBLE (8760 1535);
FORCEPROP 1 LAST HDL_POWER PVDDCR_CPU1_P1
J 1
(8750 1625);
DISPLAY 0.489362 (8750 1625);
PAINT GREEN (8750 1625);
FORCEPROP 2 LAST CDS_LIB pure_quanta_power
J 0
(8750 1575);
DISPLAY INVISIBLE (8750 1575);
FORCEPROP 1 LAST PATH I68
J 0
(8800 1600);
DISPLAY 0.872340 (8800 1600);
PAINT AQUA (8800 1600);
DISPLAY INVISIBLE (8800 1600);
FORCEADD UNIVERSAL_GND..1
(8600 3775);
FORCEPROP 3 LASTPIN (8600 3825) SIG_NAME GND\g
J 0
(8610 3835);
DISPLAY 0.659574 (8610 3835);
PAINT MONO (8610 3835);
DISPLAY INVISIBLE (8610 3835);
FORCEPROP 2 LAST CDS_LIB pure_quanta_power
J 0
(8600 3775);
PAINT MONO (8600 3775);
DISPLAY INVISIBLE (8600 3775);
FORCEPROP 1 LAST HDL_POWER GND
J 1
(8625 3700);
DISPLAY 0.872340 (8625 3700);
PAINT GREEN (8625 3700);
DISPLAY INVISIBLE (8625 3700);
FORCEPROP 1 LAST PATH I69
J 0
(8675 3775);
DISPLAY 0.872340 (8675 3775);
PAINT AQUA (8675 3775);
DISPLAY INVISIBLE (8675 3775);
FORCEADD Q_CAP..1
(1500 1925);
FORCEPROP 1 LAST LOCATION PC399
J 0
(1550 2025);
DISPLAY 0.489362 (1550 2025);
PAINT SKYBLUE (1550 2025);
FORCEPROP 0 LAST $SEC 1
J 0
(1550 2075);
DISPLAY 0.680851 (1550 2075);
PAINT MONO (1550 2075);
DISPLAY INVISIBLE (1550 2075);
FORCEPROP 0 LAST CDS_SEC 1
J 0
(1550 2075);
DISPLAY 1.021277 (1550 2075);
DISPLAY INVISIBLE (1550 2075);
FORCEPROP 1 LASTPIN (1500 2025) $PN 1
J 0
(1510 2005);
DISPLAY 0.489362 (1510 2005);
PAINT MONO (1510 2005);
FORCEPROP 1 LASTPIN (1500 1825) $PN 2
J 0
(1510 1805);
DISPLAY 0.489362 (1510 1805);
PAINT MONO (1510 1805);
FORCEPROP 1 LAST MATERIAL X6S
J 0
(1550 1825);
DISPLAY 0.489362 (1550 1825);
PAINT SKYBLUE (1550 1825);
FORCEPROP 1 LAST TOLERANCE 10%
J 0
(1550 1875);
DISPLAY 0.489362 (1550 1875);
PAINT SKYBLUE (1550 1875);
FORCEPROP 1 LAST VALUE 2.2UF
J 0
(1550 1975);
DISPLAY 0.489362 (1550 1975);
PAINT SKYBLUE (1550 1975);
FORCEPROP 1 LAST VOLTAGE 10V
J 0
(1550 1925);
DISPLAY 0.489362 (1550 1925);
PAINT SKYBLUE (1550 1925);
FORCEPROP 1 LAST PACK_TYPE C0402
J 0
(1550 1725);
DISPLAY 0.489362 (1550 1725);
PAINT SKYBLUE (1550 1725);
FORCEPROP 2 LAST CDS_LIB pure_quanta
J 0
(1500 1925);
DISPLAY INVISIBLE (1500 1925);
FORCEPROP 1 LAST PATH I7
J 0
(1550 2075);
DISPLAY 0.978723 (1550 2075);
PAINT WHITE (1550 2075);
DISPLAY INVISIBLE (1550 2075);
FORCEPROP 1 LAST PART_NUMBER CH5222KEB01
J 0
(1550 1775);
DISPLAY 0.489362 (1550 1775);
PAINT SKYBLUE (1550 1775);
DISPLAY INVISIBLE (1550 1775);
FORCEADD Q_CAP..1
(8600 4100);
FORCEPROP 1 LAST LOCATION PC419_3
J 0
(8650 4225);
DISPLAY 0.489362 (8650 4225);
PAINT SKYBLUE (8650 4225);
FORCEPROP 0 LAST $SEC 1
J 0
(8650 4275);
DISPLAY 0.680851 (8650 4275);
PAINT MONO (8650 4275);
DISPLAY INVISIBLE (8650 4275);
FORCEPROP 0 LAST CDS_SEC 1
J 0
(8650 4275);
DISPLAY 1.021277 (8650 4275);
DISPLAY INVISIBLE (8650 4275);
FORCEPROP 1 LASTPIN (8600 4200) $PN 1
J 0
(8610 4180);
DISPLAY 0.489362 (8610 4180);
PAINT MONO (8610 4180);
FORCEPROP 1 LASTPIN (8600 4000) $PN 2
J 0
(8610 3980);
DISPLAY 0.489362 (8610 3980);
PAINT MONO (8610 3980);
FORCEPROP 1 LAST VOLTAGE 4V
J 0
(8650 4125);
DISPLAY 0.489362 (8650 4125);
PAINT SKYBLUE (8650 4125);
FORCEPROP 1 LAST VALUE 22UF
J 0
(8650 4175);
DISPLAY 0.489362 (8650 4175);
PAINT SKYBLUE (8650 4175);
FORCEPROP 1 LAST TOLERANCE 20%
J 0
(8650 4075);
DISPLAY 0.489362 (8650 4075);
PAINT SKYBLUE (8650 4075);
FORCEPROP 1 LAST MATERIAL X6S
J 0
(8650 4025);
DISPLAY 0.489362 (8650 4025);
PAINT SKYBLUE (8650 4025);
FORCEPROP 1 LAST PACK_TYPE C0805
J 0
(8650 3975);
DISPLAY 0.489362 (8650 3975);
PAINT SKYBLUE (8650 3975);
FORCEPROP 2 LAST CDS_LIB pure_quanta
J 0
(8600 4100);
DISPLAY INVISIBLE (8600 4100);
FORCEPROP 1 LAST PATH I70
J 0
(8650 4250);
DISPLAY 0.978723 (8650 4250);
PAINT WHITE (8650 4250);
DISPLAY INVISIBLE (8650 4250);
FORCEPROP 1 LAST PART_NUMBER CH622KMEA03
J 0
(8650 3925);
DISPLAY 0.489362 (8650 3925);
PAINT SKYBLUE (8650 3925);
DISPLAY INVISIBLE (8650 3925);
FORCEADD VCC_CORE..1
(8600 4400);
FORCEPROP 3 LASTPIN (8600 4350) SIG_NAME PVDDCR_CPU1_P1\g
J 0
(8610 4360);
DISPLAY 0.659574 (8610 4360);
PAINT MONO (8610 4360);
DISPLAY INVISIBLE (8610 4360);
FORCEPROP 1 LAST HDL_POWER PVDDCR_CPU1_P1
J 1
(8600 4450);
DISPLAY 0.489362 (8600 4450);
PAINT GREEN (8600 4450);
FORCEPROP 2 LAST CDS_LIB pure_quanta_power
J 0
(8600 4400);
DISPLAY INVISIBLE (8600 4400);
FORCEPROP 1 LAST PATH I71
J 0
(8650 4425);
DISPLAY 0.872340 (8650 4425);
PAINT AQUA (8650 4425);
DISPLAY INVISIBLE (8650 4425);
FORCEADD ISL99390FRZTR5935..1
(3300 4300);
FORCEPROP 1 LAST LOCATION PU37
J 0
(3000 5175);
DISPLAY 0.489362 (3000 5175);
PAINT SKYBLUE (3000 5175);
FORCEPROP 2 LAST $SEC 1
J 0
(3000 5225);
DISPLAY 0.680851 (3000 5225);
PAINT MONO (3000 5225);
DISPLAY INVISIBLE (3000 5225);
FORCEPROP 2 LAST CDS_SEC 1
J 0
(3000 5225);
DISPLAY 1.021277 (3000 5225);
DISPLAY INVISIBLE (3000 5225);
FORCEPROP 2 LASTPIN (3700 3850) $PN 2
J 0
(3710 3860);
DISPLAY 0.489362 (3710 3860);
PAINT MONO (3710 3860);
FORCEPROP 2 LASTPIN (3700 4650) $PN 33
J 0
(3710 4660);
DISPLAY 0.489362 (3710 4660);
PAINT MONO (3710 4660);
FORCEPROP 2 LASTPIN (2850 4050) $PN 31
J 2
(2840 4060);
DISPLAY 0.489362 (2840 4060);
PAINT MONO (2840 4060);
FORCEPROP 2 LASTPIN (2850 4450) $PN 35
J 2
(2840 4460);
DISPLAY 0.489362 (2840 4460);
PAINT MONO (2840 4460);
FORCEPROP 2 LASTPIN (3700 4000) $PN 6
J 0
(3710 4010);
DISPLAY 0.489362 (3710 4010);
PAINT MONO (3710 4010);
FORCEPROP 2 LASTPIN (3700 3950) $PN 41
J 0
(3710 3960);
DISPLAY 0.489362 (3710 3960);
PAINT MONO (3710 3960);
FORCEPROP 2 LASTPIN (2850 4300) $PN 38
J 2
(2840 4310);
DISPLAY 0.489362 (2840 4310);
PAINT MONO (2840 4310);
FORCEPROP 2 LASTPIN (2850 4000) $PN 37
J 2
(2840 4010);
DISPLAY 0.489362 (2840 4010);
PAINT MONO (2840 4010);
FORCEPROP 2 LASTPIN (3700 3800) $PN 5
J 0
(3710 3810);
DISPLAY 0.489362 (3710 3810);
PAINT MONO (3710 3810);
FORCEPROP 2 LASTPIN (3700 3750) $PN 7_9-20_24
J 0
(3710 3760);
DISPLAY 0.489362 (3710 3760);
PAINT MONO (3710 3760);
FORCEPROP 2 LASTPIN (3700 3700) $PN 40
J 0
(3710 3710);
DISPLAY 0.489362 (3710 3710);
PAINT MONO (3710 3710);
FORCEPROP 2 LASTPIN (3700 4400) $PN 32
J 0
(3710 4410);
DISPLAY 0.489362 (3710 4410);
PAINT MONO (3710 4410);
FORCEPROP 2 LASTPIN (2850 4950) $PN 4
J 2
(2840 4960);
DISPLAY 0.489362 (2840 4960);
PAINT MONO (2840 4960);
FORCEPROP 2 LASTPIN (2850 3700) $PN 34
J 2
(2840 3710);
DISPLAY 0.489362 (2840 3710);
PAINT MONO (2840 3710);
FORCEPROP 2 LASTPIN (2850 4200) $PN 39
J 2
(2840 4210);
DISPLAY 0.489362 (2840 4210);
PAINT MONO (2840 4210);
FORCEPROP 2 LASTPIN (3700 4300) $PN 10_19
J 0
(3710 4310);
DISPLAY 0.489362 (3710 4310);
PAINT MONO (3710 4310);
FORCEPROP 2 LASTPIN (2850 3800) $PN 36
J 2
(2840 3810);
DISPLAY 0.489362 (2840 3810);
PAINT MONO (2840 3810);
FORCEPROP 2 LASTPIN (2850 4650) $PN 3
J 2
(2840 4660);
DISPLAY 0.489362 (2840 4660);
PAINT MONO (2840 4660);
FORCEPROP 2 LASTPIN (3700 4950) $PN 25_29
J 0
(3710 4960);
DISPLAY 0.489362 (3710 4960);
PAINT MONO (3710 4960);
FORCEPROP 2 LASTPIN (3700 4900) $PN 30
J 0
(3710 4910);
DISPLAY 0.489362 (3710 4910);
PAINT MONO (3710 4910);
FORCEPROP 2 LASTPIN (3700 4050) $PN 1
J 0
(3710 4060);
DISPLAY 0.489362 (3710 4060);
PAINT MONO (3710 4060);
FORCEPROP 2 LAST PART_TYPE SMLF
J 0
(3000 5325);
DISPLAY 0.638298 (3000 5325);
FORCEPROP 1 LAST MATERIAL IC
J 0
(3000 5025);
DISPLAY 0.489362 (3000 5025);
PAINT SKYBLUE (3000 5025);
FORCEPROP 2 LAST VALUE ISL99390FRZ-TR5935
J 0
(3000 5275);
DISPLAY 0.489362 (3000 5275);
PAINT SKYBLUE (3000 5275);
FORCEPROP 2 LAST CDS_LIB pure_quanta
J 0
(3300 4300);
DISPLAY INVISIBLE (3300 4300);
FORCEPROP 1 LAST CDS_LMAN_SYM_OUTLINE -300,700,250,-650
J 0
(3300 4300);
DISPLAY 0.468085 (3300 4300);
PAINT GREEN (3300 4300);
DISPLAY INVISIBLE (3300 4300);
FORCEPROP 1 LAST NEEDS_NO_SIZE TRUE
J 0
(3300 4300);
DISPLAY 0.723404 (3300 4300);
PAINT GREEN (3300 4300);
DISPLAY INVISIBLE (3300 4300);
FORCEPROP 1 LAST PATH I72
J 0
(3300 4300);
DISPLAY 0.723404 (3300 4300);
PAINT GREEN (3300 4300);
DISPLAY INVISIBLE (3300 4300);
FORCEPROP 1 LAST PART_NUMBER AL099390004
J 0
(3000 5100);
DISPLAY 0.489362 (3000 5100);
PAINT SKYBLUE (3000 5100);
DISPLAY INVISIBLE (3000 5100);
FORCEADD OFFPAGE..5
(1825 975);
FORCEPROP 2 LAST $XR3 217 
J 0
(1570 903);
DISPLAY 0.638298 (1570 903);
PAINT MONO (1570 903);
FORCEPROP 2 LAST $XR2 220 
J 0
(1570 1011);
DISPLAY 0.638298 (1570 1011);
PAINT MONO (1570 1011);
FORCEPROP 2 LAST $XR1 219 
J 0
(1570 939);
DISPLAY 0.638298 (1570 939);
PAINT MONO (1570 939);
FORCEPROP 2 LAST $XR0 218 
J 0
(1570 975);
DISPLAY 0.638298 (1570 975);
PAINT MONO (1570 975);
FORCEPROP 2 LAST CDS_LIB standard
J 0
(1825 975);
DISPLAY INVISIBLE (1825 975);
FORCEPROP 1 LAST OFFPAGE TRUE
J 0
(2150 850);
DISPLAY 0.872340 (2150 850);
PAINT GREEN (2150 850);
DISPLAY INVISIBLE (2150 850);
FORCEPROP 1 LAST COMMENT_BODY TRUE
J 0
(1925 900);
DISPLAY 0.872340 (1925 900);
PAINT GREEN (1925 900);
DISPLAY INVISIBLE (1925 900);
FORCEPROP 2 LAST PATH I8
J 0
(1575 1100);
DISPLAY 0.680851 (1575 1100);
DISPLAY INVISIBLE (1575 1100);
FORCEADD OFFPAGE..1
(1825 1375);
FORCEPROP 2 LAST $XR5 223 
J 0
(973 1375);
DISPLAY 0.638298 (973 1375);
PAINT MONO (973 1375);
FORCEPROP 2 LAST $XR4 222 
J 0
(1093 1375);
DISPLAY 0.638298 (1093 1375);
PAINT MONO (1093 1375);
FORCEPROP 2 LAST $XR3 220 
J 0
(1213 1375);
DISPLAY 0.638298 (1213 1375);
PAINT MONO (1213 1375);
FORCEPROP 2 LAST $XR2 219 
J 0
(1333 1375);
DISPLAY 0.638298 (1333 1375);
PAINT MONO (1333 1375);
FORCEPROP 2 LAST $XR1 218 
J 0
(1453 1375);
DISPLAY 0.638298 (1453 1375);
PAINT MONO (1453 1375);
FORCEPROP 2 LAST $XR0 217 
J 0
(1573 1375);
DISPLAY 0.638298 (1573 1375);
PAINT MONO (1573 1375);
FORCEPROP 2 LAST CDS_LIB standard
J 0
(1825 1375);
DISPLAY INVISIBLE (1825 1375);
FORCEPROP 1 LAST OFFPAGE TRUE
J 0
(2150 1250);
DISPLAY 0.872340 (2150 1250);
PAINT GREEN (2150 1250);
DISPLAY INVISIBLE (2150 1250);
FORCEPROP 1 LAST COMMENT_BODY TRUE
J 0
(1950 1275);
DISPLAY 0.872340 (1950 1275);
PAINT GREEN (1950 1275);
DISPLAY INVISIBLE (1950 1275);
FORCEPROP 2 LAST PATH I9
J 0
(1550 1425);
DISPLAY 0.680851 (1550 1425);
DISPLAY INVISIBLE (1550 1425);
FORCEADD DNS..1
(4750 3550);
PAINT RED (4750 3550);
FORCEPROP 2 LAST CDS_LIB mstr_misc
J 0
(4750 3550);
DISPLAY INVISIBLE (4750 3550);
FORCEPROP 1 LAST COMMENT_BODY TRUE
R 1
J 0
(4825 3325);
DISPLAY 0.872340 (4825 3325);
PAINT GREEN (4825 3325);
DISPLAY INVISIBLE (4825 3325);
FORCEADD DNS..1
(4750 4100);
PAINT RED (4750 4100);
FORCEPROP 2 LAST CDS_LIB mstr_misc
J 0
(4750 4100);
DISPLAY INVISIBLE (4750 4100);
FORCEPROP 1 LAST COMMENT_BODY TRUE
R 1
J 0
(4825 3875);
DISPLAY 0.872340 (4825 3875);
PAINT GREEN (4825 3875);
DISPLAY INVISIBLE (4825 3875);
FORCEADD DNS..1
(4650 1275);
PAINT RED (4650 1275);
FORCEPROP 2 LAST CDS_LIB mstr_misc
J 0
(4650 1275);
DISPLAY INVISIBLE (4650 1275);
FORCEPROP 1 LAST COMMENT_BODY TRUE
R 1
J 0
(4725 1050);
DISPLAY 0.872340 (4725 1050);
PAINT GREEN (4725 1050);
DISPLAY INVISIBLE (4725 1050);
FORCEADD DNS..1
(4650 775);
PAINT RED (4650 775);
FORCEPROP 2 LAST CDS_LIB mstr_misc
J 0
(4650 775);
DISPLAY INVISIBLE (4650 775);
FORCEPROP 1 LAST COMMENT_BODY TRUE
R 1
J 0
(4725 550);
DISPLAY 0.872340 (4725 550);
PAINT GREEN (4725 550);
DISPLAY INVISIBLE (4725 550);
FORCEADD DNS..1
(1375 3775);
PAINT RED (1375 3775);
FORCEPROP 2 LAST CDS_LIB mstr_misc
J 0
(1375 3775);
PAINT MONO (1375 3775);
DISPLAY INVISIBLE (1375 3775);
FORCEPROP 1 LAST COMMENT_BODY TRUE
R 1
J 0
(1450 3550);
DISPLAY 0.872340 (1450 3550);
PAINT GREEN (1450 3550);
DISPLAY INVISIBLE (1450 3550);
FORCEADD DNS..1
(1350 950);
PAINT RED (1350 950);
FORCEPROP 2 LAST CDS_LIB mstr_misc
J 0
(1350 950);
PAINT MONO (1350 950);
DISPLAY INVISIBLE (1350 950);
FORCEPROP 1 LAST COMMENT_BODY TRUE
R 1
J 0
(1425 725);
DISPLAY 0.872340 (1425 725);
PAINT GREEN (1425 725);
DISPLAY INVISIBLE (1425 725);
FORCEADD QUANTA_TITLE_BLOCK_C..1
(9375 -450);
FORCEPROP 0 LAST CDS_CON_LAST_MODIFIED Thu Sep 14 16:12:21 2023
J 0
(7490 -435);
DISPLAY INVISIBLE (7490 -435);
FORCEPROP 1 LAST CUSTOM_TXT_CDS <CON_LAST_MODIFIED>
J 0
(7490 -435);
DISPLAY 0.978723 (7490 -435);
FORCEPROP 2 LAST CUSTOM_TXT_CDS <XR_PAGE_TITLE>
J 0
(1485 4800);
DISPLAY 0.638298 (1485 4800);
PAINT PINK (1485 4800);
DISPLAY INVISIBLE (1485 4800);
FORCEPROP 1 LAST CUSTOM_TXT_CDS <NAME_2>
J 0
(6200 -400);
FORCEPROP 1 LAST CUSTOM_TXT_CDS <NAME_1>
J 0
(6200 -275);
FORCEPROP 1 LAST CUSTOM_TXT_CDS <Q_NUMBER>
J 0
(7972 -347);
DISPLAY 1.212766 (7972 -347);
FORCEPROP 1 LAST CUSTOM_TXT_CDS <Q_PROJ>
J 0
(6993 -348);
DISPLAY 1.212766 (6993 -348);
FORCEPROP 1 LAST CUSTOM_TXT_CDS <Q_REV>
J 0
(9191 -347);
DISPLAY 1.212766 (9191 -347);
FORCEPROP 1 LAST CUSTOM_TXT_CDS <CON_PAGE_NUM> OF <CON_TOTAL_PAGES>
J 0
(8929 -432);
DISPLAY 0.978723 (8929 -432);
FORCEPROP 1 LAST Q_TITLE PVDDCR_CPU1_P1 VR PHASE 3&4
J 0
(75 -400);
DISPLAY 2.446809 (75 -400);
PAINT GREEN (75 -400);
FORCEPROP 2 LAST PAGE_BORDER TRUE
J 0
(1485 4800);
DISPLAY 0.638298 (1485 4800);
PAINT PINK (1485 4800);
DISPLAY INVISIBLE (1485 4800);
FORCEPROP 2 LAST CDS_LIB pure_quanta
J 0
(9375 -450);
DISPLAY INVISIBLE (9375 -450);
FORCEPROP 1 LAST CDS_LMAN_SYM_OUTLINE -9475,6775,100,-125
J 0
(9375 -450);
DISPLAY 0.468085 (9375 -450);
PAINT GREEN (9375 -450);
DISPLAY INVISIBLE (9375 -450);
FORCEPROP 2 LAST CDS_XR_PAGE_TITLE CR-219 : @T6G_MB_LIB.T6G(SCH_1):PAGE219
J 0
(1485 4800);
DISPLAY 0.638298 (1485 4800);
PAINT PINK (1485 4800);
DISPLAY INVISIBLE (1485 4800);
FORCEPROP 1 LAST Q_DEPT BU9
J 1
(5612 -401);
DISPLAY 1.957447 (5612 -401);
PAINT GREEN (5612 -401);
DISPLAY INVISIBLE (5612 -401);
FORCEPROP 1 LAST COMMENT_BODY TRUE
J 0
(9387 -463);
DISPLAY 0.978723 (9387 -463);
PAINT GREEN (9387 -463);
DISPLAY INVISIBLE (9387 -463);
WIRE 16 -1 (850 950)(850 1000);
WIRE 16 -1 (875 3775)(875 3825);
WIRE 16 -1 (1850 2400)(1850 2275);
WIRE 16 -1 (1375 3700)(1375 3625);
WIRE 16 -1 (1675 4650)(1675 4600);
WIRE 16 -1 (1350 875)(1350 800);
WIRE 16 -1 (2025 5225)(2025 5100);
WIRE 16 -1 (4675 675)(4675 600);
WIRE 16 -1 (4775 3450)(4775 3375);
WIRE 16 -1 (1500 1825)(1500 1775);
WIRE 16 -1 (5650 2275)(5650 2125);
WIRE 16 -1 (5650 2050)(5650 2125);
WIRE 16 -1 (5275 2125)(5650 2125);
WIRE 16 -1 (5275 2275)(5275 2125);
WIRE 16 -1 (4875 2125)(5275 2125);
WIRE 16 -1 (4875 2275)(4875 2125);
WIRE 16 -1 (4875 2125)(4475 2125);
WIRE 16 -1 (4475 2275)(4475 2125);
WIRE 16 -1 (4075 2125)(4475 2125);
WIRE 16 -1 (4075 2300)(4075 2125);
WIRE 16 -1 (3675 2075)(3850 2075);
WIRE 16 -1 (3850 2075)(3850 2125);
WIRE 16 -1 (3850 2625)(3850 2125);
WIRE 16 -1 (3675 2125)(3850 2125);
WIRE 16 -1 (4075 2625)(3850 2625);
WIRE 16 -1 (4475 2625)(4075 2625);
WIRE 16 -1 (4075 2500)(4075 2625);
WIRE 16 -1 (4475 2625)(4875 2625);
WIRE 16 -1 (4475 2475)(4475 2625);
WIRE 16 -1 (4875 2625)(5275 2625);
WIRE 16 -1 (4875 2625)(4875 2475);
WIRE 16 -1 (5275 2625)(5650 2625);
WIRE 16 -1 (5275 2475)(5275 2625);
WIRE 16 -1 (5650 2675)(5650 2625);
WIRE 16 -1 (5650 2475)(5650 2625);
WIRE 16 -1 (4475 3125)(5800 3125);
WIRE 16 -1 (4475 4050)(4475 3125);
WIRE 16 -1 (3700 4050)(4475 4050);
FORCEPROP 2 LAST SIG_NAME PVDDCR_CPU1_P1_VOS3
J 0
(3790 4075);
DISPLAY 0.489362 (3790 4075);
FORCEPROP 2 LASTPROP $XRERR UNIQUE?
J 0
(3550 4075);
DISPLAY 0.638298 (3550 4075);
PAINT MONO (3550 4075);
DISPLAY INVISIBLE (3550 4075);
WIRE 16 -1 (4775 4200)(4775 4300);
WIRE 16 -1 (4775 4300)(6300 4300);
WIRE 16 -1 (3700 4300)(4775 4300);
FORCEPROP 2 LAST SIG_NAME SW_PVDDCR_CPU1_P1_SW3
J 0
(3890 4310);
DISPLAY 0.489362 (3890 4310);
FORCEPROP 2 LASTPROP $XRERR UNIQUE?
J 0
(3650 4310);
DISPLAY 0.638298 (3650 4310);
PAINT MONO (3650 4310);
DISPLAY INVISIBLE (3650 4310);
WIRE 16 -1 (5650 4400)(5650 4425);
WIRE 16 -1 (3700 4400)(5650 4400);
FORCEPROP 2 LAST SIG_NAME SW_PVDDCR_CPU1_P1_BOOTR3
J 0
(3890 4410);
DISPLAY 0.489362 (3890 4410);
FORCEPROP 2 LASTPROP $XRERR UNIQUE?
J 0
(3650 4410);
DISPLAY 0.638298 (3650 4410);
PAINT MONO (3650 4410);
DISPLAY INVISIBLE (3650 4410);
WIRE 16 -1 (4125 5150)(4125 4975);
WIRE 16 -1 (4125 4975)(4525 4975);
WIRE 16 -1 (4525 5125)(4525 4975);
WIRE 16 -1 (4925 4975)(4525 4975);
WIRE 16 -1 (4925 4975)(5325 4975);
WIRE 16 -1 (4925 5125)(4925 4975);
WIRE 16 -1 (5325 5125)(5325 4975);
WIRE 16 -1 (5325 4975)(5700 4975);
WIRE 16 -1 (5700 5125)(5700 4975);
WIRE 16 -1 (5700 4925)(5700 4975);
WIRE 16 -1 (5650 4650)(5650 4625);
WIRE 16 -1 (4775 4650)(5650 4650);
FORCEPROP 2 LAST SIG_NAME SW_PVDDCR_CPU1_P1_BOOT3_R
J 0
(4890 4660);
DISPLAY 0.489362 (4890 4660);
FORCEPROP 2 LASTPROP $XRERR UNIQUE?
J 0
(4650 4660);
DISPLAY 0.638298 (4650 4660);
PAINT MONO (4650 4660);
DISPLAY INVISIBLE (4650 4660);
WIRE 16 -1 (3675 1825)(4500 1825);
FORCEPROP 2 LAST SIG_NAME SW_PVDDCR_CPU1_P1_BOOT4
J 0
(3840 1835);
DISPLAY 0.489362 (3840 1835);
FORCEPROP 2 LASTPROP $XRERR UNIQUE?
J 0
(3600 1835);
DISPLAY 0.638298 (3600 1835);
PAINT MONO (3600 1835);
DISPLAY INVISIBLE (3600 1835);
WIRE 16 -1 (5500 1825)(5500 1800);
WIRE 16 -1 (4700 1825)(5500 1825);
FORCEPROP 2 LAST SIG_NAME SW_PVDDCR_CPU1_P1_BOOT4_R
J 0
(4915 1835);
DISPLAY 0.489362 (4915 1835);
FORCEPROP 2 LASTPROP $XRERR UNIQUE?
J 0
(4675 1835);
DISPLAY 0.638298 (4675 1835);
PAINT MONO (4675 1835);
DISPLAY INVISIBLE (4675 1835);
WIRE 16 -1 (3700 4650)(4575 4650);
FORCEPROP 2 LAST SIG_NAME SW_PVDDCR_CPU1_P1_BOOT3
J 0
(3865 4660);
DISPLAY 0.489362 (3865 4660);
FORCEPROP 2 LASTPROP $XRERR UNIQUE?
J 0
(3625 4660);
DISPLAY 0.638298 (3625 4660);
PAINT MONO (3625 4660);
DISPLAY INVISIBLE (3625 4660);
WIRE 16 -1 (8600 4200)(8600 4300);
WIRE 16 -1 (8600 4350)(8600 4300);
WIRE 16 -1 (8175 4300)(8600 4300);
WIRE 16 -1 (8175 4300)(8175 4200);
WIRE 16 -1 (8175 4300)(8050 4300);
WIRE 16 -1 (8050 4300)(7100 4300);
WIRE 16 -1 (8050 3125)(8050 4300);
WIRE 16 -1 (6000 3125)(8050 3125);
WIRE 16 -1 (8600 4000)(8600 3875);
WIRE 16 -1 (8600 3825)(8600 3875);
WIRE 16 -1 (8600 3875)(8175 3875);
WIRE 16 -1 (8175 3875)(8175 4000);
WIRE 16 -1 (8750 1525)(8750 1475);
WIRE 16 -1 (8750 1475)(8750 1375);
WIRE 16 -1 (8325 1475)(8750 1475);
WIRE 16 -1 (8325 1475)(8325 1375);
WIRE 16 -1 (7875 1475)(8325 1475);
WIRE 16 -1 (7875 475)(7875 1475);
WIRE 16 -1 (7050 1475)(7875 1475);
WIRE 16 -1 (7875 475)(6075 475);
WIRE 16 -1 (8750 1050)(8750 1175);
WIRE 16 -1 (8750 1050)(8325 1050);
WIRE 16 -1 (8750 1000)(8750 1050);
WIRE 16 -1 (8325 1050)(8325 1175);
WIRE 16 -1 (5700 5325)(5700 5475);
WIRE 16 -1 (5700 5525)(5700 5475);
WIRE 16 -1 (5325 5475)(5700 5475);
WIRE 16 -1 (5325 5325)(5325 5475);
WIRE 16 -1 (4925 5475)(5325 5475);
WIRE 16 -1 (4925 5475)(4925 5325);
WIRE 16 -1 (4525 5475)(4925 5475);
WIRE 16 -1 (4525 5325)(4525 5475);
WIRE 16 -1 (4525 5475)(4125 5475);
WIRE 16 -1 (4125 5350)(4125 5475);
WIRE 16 -1 (4125 5475)(3875 5475);
WIRE 16 -1 (3875 5475)(3875 4950);
WIRE 16 -1 (3875 4900)(3875 4950);
WIRE 16 -1 (3700 4950)(3875 4950);
WIRE 16 -1 (3700 4900)(3875 4900);
WIRE 16 -1 (7050 1225)(7525 1225);
WIRE 16 -1 (7525 1175)(7525 1225);
WIRE 16 -1 (1675 5400)(1675 5525);
WIRE 16 -1 (1675 5650)(1675 5525);
WIRE 16 -1 (2025 5525)(1675 5525);
WIRE 16 -1 (2350 5525)(2025 5525);
WIRE 16 -1 (2025 5425)(2025 5525);
WIRE 16 -1 (2350 4950)(2350 5525);
WIRE 16 -1 (2850 4950)(2350 4950);
WIRE 16 -1 (3700 3750)(3950 3750);
WIRE 16 -1 (3950 3800)(3950 3750);
WIRE 16 -1 (3950 3750)(3950 3700);
WIRE 16 -1 (3700 3700)(3950 3700);
WIRE 16 -1 (3950 3700)(3950 3625);
WIRE 16 -1 (3950 3850)(3950 3800);
WIRE 16 -1 (3700 3800)(3950 3800);
WIRE 16 -1 (3700 3850)(3950 3850);
WIRE 16 -1 (3675 925)(3925 925);
WIRE 16 -1 (3925 975)(3925 925);
WIRE 16 -1 (3925 925)(3925 875);
WIRE 16 -1 (3675 875)(3925 875);
WIRE 16 -1 (3925 875)(3925 800);
WIRE 16 -1 (3925 1025)(3925 975);
WIRE 16 -1 (3675 975)(3925 975);
WIRE 16 -1 (3675 1025)(3925 1025);
WIRE 16 -1 (1500 2575)(1500 2700);
WIRE 16 -1 (1850 2700)(1500 2700);
WIRE 16 -1 (1500 2825)(1500 2700);
WIRE 16 -1 (2750 2700)(1850 2700);
WIRE 16 -1 (1850 2600)(1850 2700);
WIRE 16 -1 (2750 2125)(2750 2700);
WIRE 16 -1 (2825 2125)(2750 2125);
WIRE 16 -1 (2825 1475)(1875 1475);
FORCEPROP 2 LAST SIG_NAME PVDDCR_CPU1_P1_IMON4
J 0
(1990 1485);
DISPLAY 0.489362 (1990 1485);
WIRE 16 -1 (2825 1625)(2725 1625);
WIRE 16 -1 (2725 1625)(2725 1825);
WIRE 16 -1 (2825 1825)(2725 1825);
WIRE 16 -1 (2725 1825)(2075 1825);
FORCEPROP 2 LAST SIG_NAME PVDDCR_CPU1_P1_VCC4
J 0
(2190 1835);
DISPLAY 0.489362 (2190 1835);
FORCEPROP 2 LASTPROP $XRERR UNIQUE?
J 0
(1950 1835);
DISPLAY 0.638298 (1950 1835);
PAINT MONO (1950 1835);
DISPLAY INVISIBLE (1950 1835);
WIRE 16 -1 (2075 2100)(2075 1825);
WIRE 16 -1 (1500 2100)(2075 2100);
WIRE 16 -1 (1500 2375)(1500 2100);
WIRE 16 -1 (1500 2100)(1500 2025);
WIRE 16 -1 (4775 4000)(4775 3650);
FORCEPROP 2 LAST SIG_NAME SW_PVDDCR_CPU1_P1_SW3_RC
J 0
(4815 3785);
DISPLAY 0.489362 (4815 3785);
FORCEPROP 2 LASTPROP $XRERR UNIQUE?
J 0
(4575 3785);
DISPLAY 0.638298 (4575 3785);
PAINT MONO (4575 3785);
DISPLAY INVISIBLE (4575 3785);
WIRE 16 -1 (3675 1225)(4450 1225);
FORCEPROP 2 LAST SIG_NAME PVDDCR_CPU1_P1_VOS4
J 0
(3790 1250);
DISPLAY 0.489362 (3790 1250);
FORCEPROP 2 LASTPROP $XRERR UNIQUE?
J 0
(3550 1250);
DISPLAY 0.638298 (3550 1250);
PAINT MONO (3550 1250);
DISPLAY INVISIBLE (3550 1250);
WIRE 16 -1 (4450 1225)(4450 475);
WIRE 16 -1 (4450 475)(5875 475);
WIRE 16 -1 (3675 1125)(4250 1125);
FORCEPROP 2 LAST SIG_NAME NC_PVDDCR_CPU1_P1_GL2_4
J 0
(3790 1135);
DISPLAY 0.489362 (3790 1135);
FORCEPROP 2 LASTPROP $XRERR UNIQUE?
J 0
(4280 1125);
DISPLAY 0.638298 (4280 1125);
PAINT MONO (4280 1125);
DISPLAY INVISIBLE (4280 1125);
WIRE 16 -1 (3675 1575)(5500 1575);
FORCEPROP 2 LAST SIG_NAME SW_PVDDCR_CPU1_P1_BOOTR4
J 0
(3865 1585);
DISPLAY 0.489362 (3865 1585);
FORCEPROP 2 LASTPROP $XRERR UNIQUE?
J 0
(3625 1585);
DISPLAY 0.638298 (3625 1585);
PAINT MONO (3625 1585);
DISPLAY INVISIBLE (3625 1585);
WIRE 16 -1 (5500 1575)(5500 1600);
WIRE 16 -1 (3675 1475)(4675 1475);
FORCEPROP 2 LAST SIG_NAME SW_PVDDCR_CPU1_P1_SW4
J 0
(3865 1485);
DISPLAY 0.489362 (3865 1485);
FORCEPROP 2 LASTPROP $XRERR UNIQUE?
J 0
(3625 1485);
DISPLAY 0.638298 (3625 1485);
PAINT MONO (3625 1485);
DISPLAY INVISIBLE (3625 1485);
WIRE 16 -1 (4675 1475)(6250 1475);
WIRE 16 -1 (4675 1375)(4675 1475);
WIRE 16 -1 (4225 4000)(3700 4000);
FORCEPROP 2 LAST SIG_NAME NC_PVDDCR_CPU1_P1_GL1_3
J 0
(3790 4010);
DISPLAY 0.489362 (3790 4010);
FORCEPROP 2 LASTPROP $XRERR UNIQUE?
J 0
(4255 4000);
DISPLAY 0.638298 (4255 4000);
PAINT MONO (4255 4000);
DISPLAY INVISIBLE (4255 4000);
WIRE 16 -1 (4225 3950)(3700 3950);
FORCEPROP 2 LAST SIG_NAME NC_PVDDCR_CPU1_P1_GL2_3
J 0
(3790 3960);
DISPLAY 0.489362 (3790 3960);
FORCEPROP 2 LASTPROP $XRERR UNIQUE?
J 0
(4255 3950);
DISPLAY 0.638298 (4255 3950);
PAINT MONO (4255 3950);
DISPLAY INVISIBLE (4255 3950);
WIRE 16 -1 (7100 4050)(7625 4050);
FORCEPROP 2 LAST SIG_NAME IND_CPU1_P1_CPL3
J 0
(7190 4060);
DISPLAY 0.489362 (7190 4060);
WIRE 16 -1 (5650 4050)(6300 4050);
FORCEPROP 2 LAST SIG_NAME IND_CPU1_P1_CPL2
J 0
(5815 4060);
DISPLAY 0.489362 (5815 4060);
WIRE 16 -1 (5725 1225)(6250 1225);
FORCEPROP 2 LAST SIG_NAME IND_CPU1_P1_CPL3
J 0
(5790 1235);
DISPLAY 0.489362 (5790 1235);
WIRE 16 -1 (4675 1175)(4675 875);
FORCEPROP 2 LAST SIG_NAME SW_PVDDCR_CPU1_P1_SW4_RC
J 0
(4715 985);
DISPLAY 0.489362 (4715 985);
FORCEPROP 2 LASTPROP $XRERR UNIQUE?
J 0
(4475 985);
DISPLAY 0.638298 (4475 985);
PAINT MONO (4475 985);
DISPLAY INVISIBLE (4475 985);
WIRE 16 -1 (3675 1175)(4250 1175);
FORCEPROP 2 LAST SIG_NAME NC_PVDDCR_CPU1_P1_GL1_4
J 0
(3790 1185);
DISPLAY 0.489362 (3790 1185);
FORCEPROP 2 LASTPROP $XRERR UNIQUE?
J 0
(4280 1175);
DISPLAY 0.638298 (4280 1175);
PAINT MONO (4280 1175);
DISPLAY INVISIBLE (4280 1175);
WIRE 16 -1 (2850 4450)(2750 4450);
WIRE 16 -1 (2750 4450)(2750 4650);
WIRE 16 -1 (2750 4650)(2850 4650);
WIRE 16 -1 (2750 4650)(2125 4650);
FORCEPROP 2 LAST SIG_NAME PVDDCR_CPU1_P1_VCC3
J 0
(2215 4660);
DISPLAY 0.489362 (2215 4660);
FORCEPROP 2 LASTPROP $XRERR UNIQUE?
J 0
(1975 4660);
DISPLAY 0.638298 (1975 4660);
PAINT MONO (1975 4660);
DISPLAY INVISIBLE (1975 4660);
WIRE 16 -1 (2125 4950)(2125 4650);
WIRE 16 -1 (1675 4950)(2125 4950);
WIRE 16 -1 (1675 5200)(1675 4950);
WIRE 16 -1 (1675 4850)(1675 4950);
WIRE 16 -1 (2850 4050)(2475 4050);
FORCEPROP 2 LAST SIG_NAME NC_PVDDCR_CPU1_P1_DNC3
J 0
(2280 4060);
DISPLAY 0.489362 (2280 4060);
FORCEPROP 2 LASTPROP $XRERR UNIQUE?
J 0
(2235 4050);
DISPLAY 0.638298 (2235 4050);
PAINT MONO (2235 4050);
DISPLAY INVISIBLE (2235 4050);
WIRE 16 -1 (2750 4200)(2750 4125);
FORCEPROP 0 LAST CDS_PHYS_NET_NAME PVDDCR_CPU1_P1_VCCS
J 0
(2750 4150);
PAINT MONO (2750 4150);
DISPLAY INVISIBLE (2750 4150);
WIRE 16 -1 (2750 4200)(2850 4200);
WIRE 16 -1 (1900 4200)(2750 4200);
FORCEPROP 2 LAST SIG_NAME PVDDCR_CPU1_P1_VCCS
J 0
(2015 4210);
DISPLAY 0.489362 (2015 4210);
WIRE 16 -1 (2750 4125)(875 4125);
WIRE 16 -1 (875 4125)(875 4025);
WIRE 16 -1 (2850 4300)(1900 4300);
FORCEPROP 2 LAST SIG_NAME PVDDCR_CPU1_P1_IMON3
J 0
(2015 4310);
DISPLAY 0.489362 (2015 4310);
WIRE 16 -1 (1375 4000)(2850 4000);
FORCEPROP 2 LAST SIG_NAME PVDDCR_CPU1_P1_LSET3
J 0
(2015 4010);
DISPLAY 0.489362 (2015 4010);
FORCEPROP 2 LASTPROP $XRERR UNIQUE?
J 0
(1775 4010);
DISPLAY 0.638298 (1775 4010);
PAINT MONO (1775 4010);
DISPLAY INVISIBLE (1775 4010);
WIRE 16 -1 (1375 4000)(1375 3900);
WIRE 16 -1 (2825 1225)(2450 1225);
FORCEPROP 2 LAST SIG_NAME NC_PVDDCR_CPU1_P1_DNC4
J 0
(2255 1235);
DISPLAY 0.489362 (2255 1235);
FORCEPROP 2 LASTPROP $XRERR UNIQUE?
J 0
(2210 1225);
DISPLAY 0.638298 (2210 1225);
PAINT MONO (2210 1225);
DISPLAY INVISIBLE (2210 1225);
WIRE 16 -1 (2725 1375)(2725 1300);
FORCEPROP 0 LAST CDS_PHYS_NET_NAME PVDDCR_CPU1_P1_VCCS
J 0
(2725 1325);
PAINT MONO (2725 1325);
DISPLAY INVISIBLE (2725 1325);
WIRE 16 -1 (2725 1375)(2825 1375);
WIRE 16 -1 (1875 1375)(2725 1375);
FORCEPROP 2 LAST SIG_NAME PVDDCR_CPU1_P1_VCCS
J 0
(1990 1385);
DISPLAY 0.489362 (1990 1385);
WIRE 16 -1 (2725 1300)(850 1300);
WIRE 16 -1 (850 1300)(850 1200);
WIRE 16 -1 (2825 975)(1875 975);
FORCEPROP 2 LAST SIG_NAME PVDDCR_CPU1_P1_TEMP0
J 0
(1990 985);
DISPLAY 0.489362 (1990 985);
WIRE 16 -1 (2825 875)(1875 875);
FORCEPROP 2 LAST SIG_NAME PVDDCR_CPU1_P1_PWM4
J 0
(1990 885);
DISPLAY 0.489362 (1990 885);
WIRE 16 -1 (2850 3700)(1900 3700);
FORCEPROP 2 LAST SIG_NAME PVDDCR_CPU1_P1_PWM3
J 0
(2015 3710);
DISPLAY 0.489362 (2015 3710);
WIRE 16 -1 (2850 3800)(1900 3800);
FORCEPROP 2 LAST SIG_NAME PVDDCR_CPU1_P1_TEMP0
J 0
(2015 3810);
DISPLAY 0.489362 (2015 3810);
WIRE 16 -1 (1350 1175)(2825 1175);
FORCEPROP 2 LAST SIG_NAME PVDDCR_CPU1_P1_LSET4
J 0
(1990 1185);
DISPLAY 0.489362 (1990 1185);
FORCEPROP 2 LASTPROP $XRERR UNIQUE?
J 0
(1750 1185);
DISPLAY 0.638298 (1750 1185);
PAINT MONO (1750 1185);
DISPLAY INVISIBLE (1750 1185);
WIRE 16 -1 (1350 1175)(1350 1075);
DOT 1 (1500 2100);
DOT 1 (1500 2700);
DOT 1 (1850 2700);
DOT 1 (2725 1375);
DOT 1 (3925 875);
DOT 1 (3925 925);
DOT 1 (3925 975);
DOT 1 (4075 2625);
DOT 1 (3950 3700);
DOT 1 (3950 3800);
DOT 1 (3950 3750);
DOT 1 (1675 4950);
DOT 1 (1675 5525);
DOT 1 (2025 5525);
DOT 1 (2750 4200);
DOT 1 (2750 4650);
DOT 1 (3875 4950);
DOT 1 (4125 5475);
DOT 1 (4675 1475);
DOT 1 (4475 2125);
DOT 1 (4475 2625);
DOT 1 (5275 2125);
DOT 1 (5650 2125);
DOT 1 (5275 2625);
DOT 1 (5650 2625);
DOT 1 (7875 1475);
DOT 1 (4775 4300);
DOT 1 (4525 5475);
DOT 1 (4925 5475);
DOT 1 (5325 4975);
DOT 1 (5700 4975);
DOT 1 (5325 5475);
DOT 1 (5700 5475);
DOT 1 (8050 4300);
DOT 1 (8175 4300);
DOT 1 (8750 1050);
DOT 1 (8325 1475);
DOT 1 (8750 1475);
DOT 1 (8600 3875);
DOT 1 (8600 4300);
DOT 1 (4525 4975);
DOT 1 (2725 1825);
DOT 1 (4875 2625);
DOT 1 (4925 4975);
DOT 1 (4875 2125);
DOT 1 (3850 2125);
FORCENOTE
11.0*7.5*12.5
(7125 1650) 0;
DISPLAY LEFT (7125 1650);
DISPLAY 0.638298 (7125 1650);
PAINT WHITE (7125 1650);
FORCENOTE
DCR=2-3,0.27M OHM
(7125 1550) 0;
DISPLAY LEFT (7125 1550);
DISPLAY 0.638298 (7125 1550);
PAINT WHITE (7125 1550);
FORCENOTE
PGL6303.151HLT
(7125 1750) 0;
DISPLAY LEFT (7125 1750);
DISPLAY 0.638298 (7125 1750);
PAINT WHITE (7125 1750);
FORCENOTE
ISAT:70A@100C
(7125 1700) 0;
DISPLAY LEFT (7125 1700);
DISPLAY 0.638298 (7125 1700);
PAINT WHITE (7125 1700);
FORCENOTE
PGL6303.151HLT
(7225 4550) 0;
DISPLAY LEFT (7225 4550);
DISPLAY 0.638298 (7225 4550);
PAINT WHITE (7225 4550);
FORCENOTE
ISAT:70A@100C
(7225 4500) 0;
DISPLAY LEFT (7225 4500);
DISPLAY 0.638298 (7225 4500);
PAINT WHITE (7225 4500);
FORCENOTE
11.0*7.5*12.5
(7225 4450) 0;
DISPLAY LEFT (7225 4450);
DISPLAY 0.638298 (7225 4450);
PAINT WHITE (7225 4450);
FORCENOTE
DCR=1-4,0.105M OHM
(7225 4400) 0;
DISPLAY LEFT (7225 4400);
DISPLAY 0.638298 (7225 4400);
PAINT WHITE (7225 4400);
FORCENOTE
DCR=2-3,0.27M OHM
(7225 4350) 0;
DISPLAY LEFT (7225 4350);
DISPLAY 0.638298 (7225 4350);
PAINT WHITE (7225 4350);
FORCENOTE
DCR=1-4,0.105M OHM
(7125 1600) 0;
DISPLAY LEFT (7125 1600);
DISPLAY 0.638298 (7125 1600);
PAINT WHITE (7125 1600);
FORCENOTE
PVDDCR_CPU1_P1_PHASE3
(2875 5500) 0;
DISPLAY LEFT (2875 5500);
DISPLAY 1.021277 (2875 5500);
PAINT WHITE (2875 5500);
FORCENOTE
PVDDCR_CPU1_P1_PHASE4
(2900 2650) 0;
DISPLAY LEFT (2900 2650);
DISPLAY 1.021277 (2900 2650);
PAINT WHITE (2900 2650);
QUIT
